(kicad_sch (version 20230121) (generator eeschema)

  (paper "A3")

  (title_block
    (title "Kria K26 Devboard")
    (date "2024-03-26")
    (rev "1.2.5")
    (comment 1 "www.antmicro.com")
    (comment 2 "Antmicro Ltd.")
  )

  (junction (at 118.745 38.1) (diameter 0) (color 0 0 0 0)
  )
  (junction (at 229.235 72.39) (diameter 0) (color 0 0 0 0)
  )
  (junction (at 177.8 152.4) (diameter 0) (color 0 0 0 0)
  )
  (junction (at 33.02 34.29) (diameter 0) (color 0 0 0 0)
  )
  (junction (at 97.155 38.1) (diameter 0) (color 0 0 0 0)
  )
  (junction (at 44.45 108.585) (diameter 0) (color 0 0 0 0)
  )
  (junction (at 243.205 72.39) (diameter 0) (color 0 0 0 0)
  )
  (junction (at 177.8 113.03) (diameter 0) (color 0 0 0 0)
  )
  (junction (at 86.36 38.1) (diameter 0) (color 0 0 0 0)
  )
  (junction (at 250.19 193.04) (diameter 0) (color 0 0 0 0)
  )
  (junction (at 177.8 72.39) (diameter 0) (color 0 0 0 0)
  )
  (junction (at 382.905 34.29) (diameter 0) (color 0 0 0 0)
  )
  (junction (at 360.68 66.04) (diameter 0) (color 0 0 0 0)
  )
  (junction (at 238.125 193.04) (diameter 0) (color 0 0 0 0)
  )
  (junction (at 44.45 89.535) (diameter 0) (color 0 0 0 0)
  )
  (junction (at 184.15 72.39) (diameter 0) (color 0 0 0 0)
  )
  (junction (at 236.855 123.19) (diameter 0) (color 0 0 0 0)
  )
  (junction (at 229.235 193.04) (diameter 0) (color 0 0 0 0)
  )
  (junction (at 97.155 41.91) (diameter 0) (color 0 0 0 0)
  )
  (junction (at 88.9 49.53) (diameter 0) (color 0 0 0 0)
  )
  (junction (at 360.68 76.2) (diameter 0) (color 0 0 0 0)
  )
  (junction (at 257.81 113.03) (diameter 0) (color 0 0 0 0)
  )
  (junction (at 370.84 66.04) (diameter 0) (color 0 0 0 0)
  )
  (junction (at 170.18 77.47) (diameter 0) (color 0 0 0 0)
  )
  (junction (at 236.855 152.4) (diameter 0) (color 0 0 0 0)
  )
  (junction (at 125.73 93.345) (diameter 0) (color 0 0 0 0)
  )
  (junction (at 360.045 44.45) (diameter 0) (color 0 0 0 0)
  )
  (junction (at 106.68 93.345) (diameter 0) (color 0 0 0 0)
  )
  (junction (at 85.09 93.345) (diameter 0) (color 0 0 0 0)
  )
  (junction (at 44.45 34.29) (diameter 0) (color 0 0 0 0)
  )
  (junction (at 95.885 104.775) (diameter 0) (color 0 0 0 0)
  )
  (junction (at 247.65 72.39) (diameter 0) (color 0 0 0 0)
  )
  (junction (at 116.205 93.345) (diameter 0) (color 0 0 0 0)
  )
  (junction (at 236.855 162.56) (diameter 0) (color 0 0 0 0)
  )
  (junction (at 184.15 113.03) (diameter 0) (color 0 0 0 0)
  )
  (junction (at 251.46 193.04) (diameter 0) (color 0 0 0 0)
  )
  (junction (at 241.935 152.4) (diameter 0) (color 0 0 0 0)
  )
  (junction (at 236.855 113.03) (diameter 0) (color 0 0 0 0)
  )
  (junction (at 125.095 250.825) (diameter 0) (color 0 0 0 0)
  )
  (junction (at 33.02 55.88) (diameter 0) (color 0 0 0 0)
  )
  (junction (at 307.34 66.04) (diameter 0) (color 0 0 0 0)
  )
  (junction (at 33.655 89.535) (diameter 0) (color 0 0 0 0)
  )
  (junction (at 118.11 93.345) (diameter 0) (color 0 0 0 0)
  )
  (junction (at 48.26 55.88) (diameter 0) (color 0 0 0 0)
  )
  (junction (at 184.15 193.04) (diameter 0) (color 0 0 0 0)
  )
  (junction (at 238.125 203.2) (diameter 0) (color 0 0 0 0)
  )
  (junction (at 352.425 34.29) (diameter 0) (color 0 0 0 0)
  )
  (junction (at 117.475 38.1) (diameter 0) (color 0 0 0 0)
  )
  (junction (at 44.45 55.88) (diameter 0) (color 0 0 0 0)
  )
  (junction (at 229.235 113.03) (diameter 0) (color 0 0 0 0)
  )
  (junction (at 55.245 55.88) (diameter 0) (color 0 0 0 0)
  )
  (junction (at 370.84 34.29) (diameter 0) (color 0 0 0 0)
  )
  (junction (at 236.855 44.45) (diameter 0) (color 0 0 0 0)
  )
  (junction (at 382.27 66.04) (diameter 0) (color 0 0 0 0)
  )
  (junction (at 229.235 34.29) (diameter 0) (color 0 0 0 0)
  )
  (junction (at 125.095 256.54) (diameter 0) (color 0 0 0 0)
  )
  (junction (at 48.26 108.585) (diameter 0) (color 0 0 0 0)
  )
  (junction (at 236.855 34.29) (diameter 0) (color 0 0 0 0)
  )
  (junction (at 360.045 34.29) (diameter 0) (color 0 0 0 0)
  )
  (junction (at 184.15 152.4) (diameter 0) (color 0 0 0 0)
  )
  (junction (at 54.61 108.585) (diameter 0) (color 0 0 0 0)
  )
  (junction (at 247.65 34.29) (diameter 0) (color 0 0 0 0)
  )
  (junction (at 125.095 262.255) (diameter 0) (color 0 0 0 0)
  )
  (junction (at 127 38.1) (diameter 0) (color 0 0 0 0)
  )
  (junction (at 86.995 141.605) (diameter 0) (color 0 0 0 0)
  )
  (junction (at 177.8 34.29) (diameter 0) (color 0 0 0 0)
  )
  (junction (at 29.845 89.535) (diameter 0) (color 0 0 0 0)
  )
  (junction (at 258.445 34.29) (diameter 0) (color 0 0 0 0)
  )
  (junction (at 33.655 108.585) (diameter 0) (color 0 0 0 0)
  )
  (junction (at 86.995 104.775) (diameter 0) (color 0 0 0 0)
  )
  (junction (at 307.34 34.29) (diameter 0) (color 0 0 0 0)
  )
  (junction (at 247.65 113.03) (diameter 0) (color 0 0 0 0)
  )
  (junction (at 97.155 49.53) (diameter 0) (color 0 0 0 0)
  )
  (junction (at 236.855 72.39) (diameter 0) (color 0 0 0 0)
  )
  (junction (at 352.425 66.04) (diameter 0) (color 0 0 0 0)
  )
  (junction (at 258.445 152.4) (diameter 0) (color 0 0 0 0)
  )
  (junction (at 303.53 34.29) (diameter 0) (color 0 0 0 0)
  )
  (junction (at 236.855 82.55) (diameter 0) (color 0 0 0 0)
  )
  (junction (at 29.21 34.29) (diameter 0) (color 0 0 0 0)
  )
  (junction (at 184.15 34.29) (diameter 0) (color 0 0 0 0)
  )
  (junction (at 300.99 39.37) (diameter 0) (color 0 0 0 0)
  )
  (junction (at 125.095 245.11) (diameter 0) (color 0 0 0 0)
  )
  (junction (at 242.57 113.03) (diameter 0) (color 0 0 0 0)
  )
  (junction (at 229.235 152.4) (diameter 0) (color 0 0 0 0)
  )
  (junction (at 107.95 38.1) (diameter 0) (color 0 0 0 0)
  )
  (junction (at 247.65 152.4) (diameter 0) (color 0 0 0 0)
  )
  (junction (at 173.99 118.11) (diameter 0) (color 0 0 0 0)
  )
  (junction (at 173.99 39.37) (diameter 0) (color 0 0 0 0)
  )
  (junction (at 248.92 34.29) (diameter 0) (color 0 0 0 0)
  )

  (no_connect (at 74.93 34.29))
  (no_connect (at 74.295 89.535))

  (wire (pts (xy 75.565 141.605) (xy 86.995 141.605))
    (stroke (width 0) (type default))
  )
  (wire (pts (xy 370.84 34.29) (xy 370.84 45.72))
    (stroke (width 0) (type default))
  )
  (wire (pts (xy 99.06 149.225) (xy 94.615 149.225))
    (stroke (width 0) (type default))
  )
  (wire (pts (xy 86.36 38.1) (xy 89.535 38.1))
    (stroke (width 0) (type default))
  )
  (wire (pts (xy 125.095 262.255) (xy 125.095 256.54))
    (stroke (width 0) (type default))
  )
  (wire (pts (xy 360.045 43.18) (xy 360.045 44.45))
    (stroke (width 0) (type default))
  )
  (wire (pts (xy 370.84 66.04) (xy 370.84 79.375))
    (stroke (width 0) (type default))
  )
  (wire (pts (xy 86.36 41.91) (xy 86.36 38.1))
    (stroke (width 0) (type default))
  )
  (wire (pts (xy 370.84 34.29) (xy 370.84 33.02))
    (stroke (width 0) (type default))
  )
  (wire (pts (xy 116.205 93.345) (xy 116.205 106.045))
    (stroke (width 0) (type default))
  )
  (wire (pts (xy 96.52 256.54) (xy 95.25 256.54))
    (stroke (width 0) (type default))
  )
  (wire (pts (xy 196.85 203.2) (xy 196.85 204.47))
    (stroke (width 0) (type default))
  )
  (wire (pts (xy 176.53 259.715) (xy 187.96 259.715))
    (stroke (width 0) (type default))
  )
  (wire (pts (xy 341.63 76.2) (xy 360.68 76.2))
    (stroke (width 0) (type default))
  )
  (wire (pts (xy 86.995 104.775) (xy 95.885 104.775))
    (stroke (width 0) (type default))
  )
  (wire (pts (xy 184.15 34.29) (xy 198.12 34.29))
    (stroke (width 0) (type default))
  )
  (wire (pts (xy 382.27 79.375) (xy 382.27 66.04))
    (stroke (width 0) (type default))
  )
  (wire (pts (xy 116.205 93.345) (xy 118.11 93.345))
    (stroke (width 0) (type default))
  )
  (wire (pts (xy 97.155 43.18) (xy 97.155 41.91))
    (stroke (width 0) (type default))
  )
  (wire (pts (xy 117.475 38.1) (xy 118.745 38.1))
    (stroke (width 0) (type default))
  )
  (wire (pts (xy 44.45 107.315) (xy 44.45 108.585))
    (stroke (width 0) (type default))
  )
  (wire (pts (xy 352.425 39.37) (xy 352.425 34.29))
    (stroke (width 0) (type default))
  )
  (wire (pts (xy 173.99 118.11) (xy 198.12 118.11))
    (stroke (width 0) (type default))
  )
  (wire (pts (xy 219.71 39.37) (xy 218.44 39.37))
    (stroke (width 0) (type default))
  )
  (wire (pts (xy 196.85 162.56) (xy 198.12 162.56))
    (stroke (width 0) (type default))
  )
  (wire (pts (xy 229.235 39.37) (xy 229.235 34.29))
    (stroke (width 0) (type default))
  )
  (wire (pts (xy 177.8 34.29) (xy 177.8 72.39))
    (stroke (width 0) (type default))
  )
  (wire (pts (xy 258.445 34.29) (xy 258.445 45.72))
    (stroke (width 0) (type default))
  )
  (wire (pts (xy 107.95 38.1) (xy 117.475 38.1))
    (stroke (width 0) (type default))
  )
  (wire (pts (xy 235.585 113.03) (xy 236.855 113.03))
    (stroke (width 0) (type default))
  )
  (wire (pts (xy 173.99 39.37) (xy 198.12 39.37))
    (stroke (width 0) (type default))
  )
  (wire (pts (xy 247.65 152.4) (xy 247.65 165.1))
    (stroke (width 0) (type default))
  )
  (wire (pts (xy 236.855 152.4) (xy 241.935 152.4))
    (stroke (width 0) (type default))
  )
  (wire (pts (xy 29.21 41.275) (xy 29.21 55.88))
    (stroke (width 0) (type default))
  )
  (wire (pts (xy 303.53 34.29) (xy 303.53 66.04))
    (stroke (width 0) (type default))
  )
  (wire (pts (xy 86.995 141.605) (xy 89.535 141.605))
    (stroke (width 0) (type default))
  )
  (wire (pts (xy 236.855 113.03) (xy 242.57 113.03))
    (stroke (width 0) (type default))
  )
  (wire (pts (xy 269.875 34.29) (xy 267.335 34.29))
    (stroke (width 0) (type default))
  )
  (wire (pts (xy 96.52 239.395) (xy 95.25 239.395))
    (stroke (width 0) (type default))
  )
  (wire (pts (xy 242.57 113.03) (xy 242.57 111.76))
    (stroke (width 0) (type default))
  )
  (wire (pts (xy 229.235 77.47) (xy 229.235 72.39))
    (stroke (width 0) (type default))
  )
  (wire (pts (xy 177.8 113.03) (xy 177.8 152.4))
    (stroke (width 0) (type default))
  )
  (wire (pts (xy 29.845 108.585) (xy 33.655 108.585))
    (stroke (width 0) (type default))
  )
  (wire (pts (xy 218.44 113.03) (xy 229.235 113.03))
    (stroke (width 0) (type default))
  )
  (wire (pts (xy 360.045 44.45) (xy 360.045 45.72))
    (stroke (width 0) (type default))
  )
  (wire (pts (xy 257.81 113.03) (xy 260.985 113.03))
    (stroke (width 0) (type default))
  )
  (wire (pts (xy 48.26 100.965) (xy 48.26 102.235))
    (stroke (width 0) (type default))
  )
  (wire (pts (xy 300.99 39.37) (xy 300.99 71.12))
    (stroke (width 0) (type default))
  )
  (wire (pts (xy 56.515 100.965) (xy 48.26 100.965))
    (stroke (width 0) (type default))
  )
  (wire (pts (xy 73.025 245.11) (xy 90.17 245.11))
    (stroke (width 0) (type default))
  )
  (wire (pts (xy 303.53 34.29) (xy 298.45 34.29))
    (stroke (width 0) (type default))
  )
  (wire (pts (xy 218.44 152.4) (xy 229.235 152.4))
    (stroke (width 0) (type default))
  )
  (wire (pts (xy 251.46 193.04) (xy 250.19 193.04))
    (stroke (width 0) (type default))
  )
  (wire (pts (xy 184.15 158.75) (xy 184.15 152.4))
    (stroke (width 0) (type default))
  )
  (wire (pts (xy 273.05 241.935) (xy 274.955 241.935))
    (stroke (width 0) (type default))
  )
  (wire (pts (xy 106.68 93.345) (xy 106.68 106.045))
    (stroke (width 0) (type default))
  )
  (wire (pts (xy 391.16 66.04) (xy 394.335 66.04))
    (stroke (width 0) (type default))
  )
  (wire (pts (xy 358.775 34.29) (xy 360.045 34.29))
    (stroke (width 0) (type default))
  )
  (wire (pts (xy 247.65 72.39) (xy 247.65 83.82))
    (stroke (width 0) (type default))
  )
  (wire (pts (xy 97.155 38.1) (xy 107.95 38.1))
    (stroke (width 0) (type default))
  )
  (wire (pts (xy 219.71 198.12) (xy 218.44 198.12))
    (stroke (width 0) (type default))
  )
  (wire (pts (xy 151.13 241.935) (xy 154.305 241.935))
    (stroke (width 0) (type default))
  )
  (wire (pts (xy 258.445 152.4) (xy 260.985 152.4))
    (stroke (width 0) (type default))
  )
  (wire (pts (xy 29.845 99.695) (xy 29.845 108.585))
    (stroke (width 0) (type default))
  )
  (wire (pts (xy 184.15 78.74) (xy 184.15 72.39))
    (stroke (width 0) (type default))
  )
  (wire (pts (xy 97.155 38.1) (xy 97.155 41.91))
    (stroke (width 0) (type default))
  )
  (wire (pts (xy 125.095 256.54) (xy 125.095 250.825))
    (stroke (width 0) (type default))
  )
  (wire (pts (xy 85.09 97.155) (xy 85.09 93.345))
    (stroke (width 0) (type default))
  )
  (wire (pts (xy 321.31 39.37) (xy 300.99 39.37))
    (stroke (width 0) (type default))
  )
  (wire (pts (xy 219.71 157.48) (xy 218.44 157.48))
    (stroke (width 0) (type default))
  )
  (wire (pts (xy 347.345 39.37) (xy 352.425 39.37))
    (stroke (width 0) (type default))
  )
  (wire (pts (xy 257.81 113.03) (xy 247.65 113.03))
    (stroke (width 0) (type default))
  )
  (wire (pts (xy 238.125 193.04) (xy 250.19 193.04))
    (stroke (width 0) (type default))
  )
  (wire (pts (xy 29.21 36.195) (xy 29.21 34.29))
    (stroke (width 0) (type default))
  )
  (wire (pts (xy 230.505 152.4) (xy 229.235 152.4))
    (stroke (width 0) (type default))
  )
  (wire (pts (xy 44.45 93.345) (xy 44.45 89.535))
    (stroke (width 0) (type default))
  )
  (wire (pts (xy 307.34 34.29) (xy 321.31 34.29))
    (stroke (width 0) (type default))
  )
  (wire (pts (xy 307.34 72.39) (xy 307.34 66.04))
    (stroke (width 0) (type default))
  )
  (wire (pts (xy 118.745 38.1) (xy 127 38.1))
    (stroke (width 0) (type default))
  )
  (wire (pts (xy 74.295 104.775) (xy 86.995 104.775))
    (stroke (width 0) (type default))
  )
  (wire (pts (xy 160.02 77.47) (xy 163.195 77.47))
    (stroke (width 0) (type default))
  )
  (wire (pts (xy 233.68 241.935) (xy 233.68 245.11))
    (stroke (width 0) (type default))
  )
  (wire (pts (xy 33.655 99.695) (xy 33.655 108.585))
    (stroke (width 0) (type default))
  )
  (wire (pts (xy 85.09 93.345) (xy 88.265 93.345))
    (stroke (width 0) (type default))
  )
  (wire (pts (xy 44.45 49.53) (xy 44.45 41.91))
    (stroke (width 0) (type default))
  )
  (wire (pts (xy 382.905 34.29) (xy 387.35 34.29))
    (stroke (width 0) (type default))
  )
  (wire (pts (xy 257.81 113.03) (xy 257.81 125.095))
    (stroke (width 0) (type default))
  )
  (wire (pts (xy 320.04 76.2) (xy 321.31 76.2))
    (stroke (width 0) (type default))
  )
  (wire (pts (xy 29.845 89.535) (xy 33.655 89.535))
    (stroke (width 0) (type default))
  )
  (wire (pts (xy 88.9 49.53) (xy 97.155 49.53))
    (stroke (width 0) (type default))
  )
  (wire (pts (xy 196.85 82.55) (xy 196.85 83.82))
    (stroke (width 0) (type default))
  )
  (wire (pts (xy 44.45 89.535) (xy 56.515 89.535))
    (stroke (width 0) (type default))
  )
  (wire (pts (xy 45.085 38.1) (xy 44.45 38.1))
    (stroke (width 0) (type default))
  )
  (wire (pts (xy 90.17 250.825) (xy 73.025 250.825))
    (stroke (width 0) (type default))
  )
  (wire (pts (xy 341.63 44.45) (xy 360.045 44.45))
    (stroke (width 0) (type default))
  )
  (wire (pts (xy 104.14 256.54) (xy 125.095 256.54))
    (stroke (width 0) (type default))
  )
  (wire (pts (xy 218.44 123.19) (xy 236.855 123.19))
    (stroke (width 0) (type default))
  )
  (wire (pts (xy 300.99 71.12) (xy 321.31 71.12))
    (stroke (width 0) (type default))
  )
  (wire (pts (xy 74.93 38.1) (xy 86.36 38.1))
    (stroke (width 0) (type default))
  )
  (wire (pts (xy 48.26 107.315) (xy 48.26 108.585))
    (stroke (width 0) (type default))
  )
  (wire (pts (xy 320.04 44.45) (xy 321.31 44.45))
    (stroke (width 0) (type default))
  )
  (wire (pts (xy 168.275 77.47) (xy 170.18 77.47))
    (stroke (width 0) (type default))
  )
  (wire (pts (xy 184.15 72.39) (xy 198.12 72.39))
    (stroke (width 0) (type default))
  )
  (wire (pts (xy 219.71 77.47) (xy 218.44 77.47))
    (stroke (width 0) (type default))
  )
  (wire (pts (xy 224.79 77.47) (xy 229.235 77.47))
    (stroke (width 0) (type default))
  )
  (wire (pts (xy 258.445 34.29) (xy 262.255 34.29))
    (stroke (width 0) (type default))
  )
  (wire (pts (xy 173.99 39.37) (xy 173.99 118.11))
    (stroke (width 0) (type default))
  )
  (wire (pts (xy 54.61 104.775) (xy 54.61 108.585))
    (stroke (width 0) (type default))
  )
  (wire (pts (xy 50.8 93.345) (xy 56.515 93.345))
    (stroke (width 0) (type default))
  )
  (wire (pts (xy 370.84 34.29) (xy 382.905 34.29))
    (stroke (width 0) (type default))
  )
  (wire (pts (xy 218.44 44.45) (xy 236.855 44.45))
    (stroke (width 0) (type default))
  )
  (wire (pts (xy 33.02 34.29) (xy 44.45 34.29))
    (stroke (width 0) (type default))
  )
  (wire (pts (xy 196.85 44.45) (xy 196.85 45.72))
    (stroke (width 0) (type default))
  )
  (wire (pts (xy 236.855 113.03) (xy 236.855 116.84))
    (stroke (width 0) (type default))
  )
  (wire (pts (xy 106.68 93.345) (xy 116.205 93.345))
    (stroke (width 0) (type default))
  )
  (wire (pts (xy 90.17 262.255) (xy 73.025 262.255))
    (stroke (width 0) (type default))
  )
  (wire (pts (xy 354.33 66.04) (xy 352.425 66.04))
    (stroke (width 0) (type default))
  )
  (wire (pts (xy 196.85 82.55) (xy 198.12 82.55))
    (stroke (width 0) (type default))
  )
  (wire (pts (xy 173.99 157.48) (xy 198.12 157.48))
    (stroke (width 0) (type default))
  )
  (wire (pts (xy 44.45 55.88) (xy 48.26 55.88))
    (stroke (width 0) (type default))
  )
  (wire (pts (xy 27.178 89.535) (xy 29.845 89.535))
    (stroke (width 0) (type default))
  )
  (wire (pts (xy 48.26 54.61) (xy 48.26 55.88))
    (stroke (width 0) (type default))
  )
  (wire (pts (xy 95.885 103.505) (xy 95.885 104.775))
    (stroke (width 0) (type default))
  )
  (wire (pts (xy 177.8 72.39) (xy 184.15 72.39))
    (stroke (width 0) (type default))
  )
  (wire (pts (xy 236.855 121.92) (xy 236.855 123.19))
    (stroke (width 0) (type default))
  )
  (wire (pts (xy 359.41 66.04) (xy 360.68 66.04))
    (stroke (width 0) (type default))
  )
  (wire (pts (xy 233.68 254.635) (xy 233.68 252.73))
    (stroke (width 0) (type default))
  )
  (wire (pts (xy 33.655 108.585) (xy 44.45 108.585))
    (stroke (width 0) (type default))
  )
  (wire (pts (xy 95.885 104.775) (xy 95.885 106.045))
    (stroke (width 0) (type default))
  )
  (wire (pts (xy 360.68 66.04) (xy 370.84 66.04))
    (stroke (width 0) (type default))
  )
  (wire (pts (xy 360.68 74.93) (xy 360.68 76.2))
    (stroke (width 0) (type default))
  )
  (wire (pts (xy 238.125 203.2) (xy 238.125 205.74))
    (stroke (width 0) (type default))
  )
  (wire (pts (xy 135.509 259.715) (xy 146.685 259.715))
    (stroke (width 0) (type default))
  )
  (wire (pts (xy 196.85 203.2) (xy 198.12 203.2))
    (stroke (width 0) (type default))
  )
  (wire (pts (xy 184.15 40.64) (xy 184.15 34.29))
    (stroke (width 0) (type default))
  )
  (wire (pts (xy 235.585 72.39) (xy 236.855 72.39))
    (stroke (width 0) (type default))
  )
  (wire (pts (xy 177.8 34.29) (xy 184.15 34.29))
    (stroke (width 0) (type default))
  )
  (wire (pts (xy 241.935 152.4) (xy 247.65 152.4))
    (stroke (width 0) (type default))
  )
  (wire (pts (xy 235.585 152.4) (xy 236.855 152.4))
    (stroke (width 0) (type default))
  )
  (wire (pts (xy 370.84 66.04) (xy 370.84 64.77))
    (stroke (width 0) (type default))
  )
  (wire (pts (xy 247.65 34.29) (xy 247.65 33.02))
    (stroke (width 0) (type default))
  )
  (wire (pts (xy 218.44 34.29) (xy 229.235 34.29))
    (stroke (width 0) (type default))
  )
  (wire (pts (xy 248.92 34.29) (xy 247.65 34.29))
    (stroke (width 0) (type default))
  )
  (wire (pts (xy 236.855 43.18) (xy 236.855 44.45))
    (stroke (width 0) (type default))
  )
  (wire (pts (xy 96.52 262.255) (xy 95.25 262.255))
    (stroke (width 0) (type default))
  )
  (wire (pts (xy 347.98 71.12) (xy 352.425 71.12))
    (stroke (width 0) (type default))
  )
  (wire (pts (xy 125.095 245.11) (xy 125.095 239.395))
    (stroke (width 0) (type default))
  )
  (wire (pts (xy 247.65 72.39) (xy 261.62 72.39))
    (stroke (width 0) (type default))
  )
  (wire (pts (xy 341.63 66.04) (xy 352.425 66.04))
    (stroke (width 0) (type default))
  )
  (wire (pts (xy 127 38.1) (xy 129.54 38.1))
    (stroke (width 0) (type default))
  )
  (wire (pts (xy 29.21 34.29) (xy 33.02 34.29))
    (stroke (width 0) (type default))
  )
  (wire (pts (xy 236.855 72.39) (xy 236.855 75.565))
    (stroke (width 0) (type default))
  )
  (wire (pts (xy 125.73 93.345) (xy 129.54 93.345))
    (stroke (width 0) (type default))
  )
  (wire (pts (xy 236.855 80.645) (xy 236.855 82.55))
    (stroke (width 0) (type default))
  )
  (wire (pts (xy 274.955 254.635) (xy 274.955 252.73))
    (stroke (width 0) (type default))
  )
  (wire (pts (xy 96.52 250.825) (xy 95.25 250.825))
    (stroke (width 0) (type default))
  )
  (wire (pts (xy 224.79 118.11) (xy 229.235 118.11))
    (stroke (width 0) (type default))
  )
  (wire (pts (xy 86.995 103.505) (xy 86.995 104.775))
    (stroke (width 0) (type default))
  )
  (wire (pts (xy 352.425 71.12) (xy 352.425 66.04))
    (stroke (width 0) (type default))
  )
  (wire (pts (xy 48.26 45.72) (xy 57.15 45.72))
    (stroke (width 0) (type default))
  )
  (wire (pts (xy 44.45 102.235) (xy 44.45 97.155))
    (stroke (width 0) (type default))
  )
  (wire (pts (xy 236.855 123.19) (xy 236.855 125.095))
    (stroke (width 0) (type default))
  )
  (wire (pts (xy 268.605 152.4) (xy 266.065 152.4))
    (stroke (width 0) (type default))
  )
  (wire (pts (xy 33.02 55.88) (xy 44.45 55.88))
    (stroke (width 0) (type default))
  )
  (wire (pts (xy 44.45 97.155) (xy 56.515 97.155))
    (stroke (width 0) (type default))
  )
  (wire (pts (xy 229.235 72.39) (xy 230.505 72.39))
    (stroke (width 0) (type default))
  )
  (wire (pts (xy 117.475 50.8) (xy 117.475 38.1))
    (stroke (width 0) (type default))
  )
  (wire (pts (xy 247.65 113.03) (xy 247.65 125.095))
    (stroke (width 0) (type default))
  )
  (wire (pts (xy 250.19 193.04) (xy 250.19 205.74))
    (stroke (width 0) (type default))
  )
  (wire (pts (xy 236.855 82.55) (xy 236.855 83.82))
    (stroke (width 0) (type default))
  )
  (wire (pts (xy 118.745 38.1) (xy 118.745 36.83))
    (stroke (width 0) (type default))
  )
  (wire (pts (xy 230.505 113.03) (xy 229.235 113.03))
    (stroke (width 0) (type default))
  )
  (wire (pts (xy 238.125 200.66) (xy 238.125 203.2))
    (stroke (width 0) (type default))
  )
  (wire (pts (xy 360.045 34.29) (xy 360.045 38.1))
    (stroke (width 0) (type default))
  )
  (polyline (pts (xy 147.32 12.7) (xy 147.32 223.52))
    (stroke (width 0) (type default))
  )

  (wire (pts (xy 134.62 38.1) (xy 135.89 38.1))
    (stroke (width 0) (type default))
  )
  (wire (pts (xy 48.26 55.88) (xy 55.245 55.88))
    (stroke (width 0) (type default))
  )
  (wire (pts (xy 395.605 34.29) (xy 392.43 34.29))
    (stroke (width 0) (type default))
  )
  (wire (pts (xy 54.61 109.855) (xy 54.61 108.585))
    (stroke (width 0) (type default))
  )
  (wire (pts (xy 360.045 34.29) (xy 370.84 34.29))
    (stroke (width 0) (type default))
  )
  (wire (pts (xy 192.405 241.935) (xy 195.58 241.935))
    (stroke (width 0) (type default))
  )
  (wire (pts (xy 74.295 97.155) (xy 75.565 97.155))
    (stroke (width 0) (type default))
  )
  (wire (pts (xy 303.53 34.29) (xy 307.34 34.29))
    (stroke (width 0) (type default))
  )
  (wire (pts (xy 93.345 93.345) (xy 106.68 93.345))
    (stroke (width 0) (type default))
  )
  (wire (pts (xy 229.235 198.12) (xy 229.235 193.04))
    (stroke (width 0) (type default))
  )
  (wire (pts (xy 224.79 39.37) (xy 229.235 39.37))
    (stroke (width 0) (type default))
  )
  (wire (pts (xy 303.53 66.04) (xy 307.34 66.04))
    (stroke (width 0) (type default))
  )
  (wire (pts (xy 86.995 97.155) (xy 86.995 98.425))
    (stroke (width 0) (type default))
  )
  (wire (pts (xy 195.58 254.635) (xy 195.58 252.73))
    (stroke (width 0) (type default))
  )
  (wire (pts (xy 56.515 104.775) (xy 54.61 104.775))
    (stroke (width 0) (type default))
  )
  (wire (pts (xy 266.7 72.39) (xy 269.875 72.39))
    (stroke (width 0) (type default))
  )
  (wire (pts (xy 184.15 199.39) (xy 184.15 193.04))
    (stroke (width 0) (type default))
  )
  (wire (pts (xy 74.93 49.53) (xy 88.9 49.53))
    (stroke (width 0) (type default))
  )
  (wire (pts (xy 127 38.1) (xy 127 50.8))
    (stroke (width 0) (type default))
  )
  (wire (pts (xy 125.095 250.825) (xy 125.095 245.11))
    (stroke (width 0) (type default))
  )
  (wire (pts (xy 382.905 34.29) (xy 382.905 45.72))
    (stroke (width 0) (type default))
  )
  (wire (pts (xy 33.02 41.275) (xy 33.02 55.88))
    (stroke (width 0) (type default))
  )
  (wire (pts (xy 236.855 34.29) (xy 236.855 38.1))
    (stroke (width 0) (type default))
  )
  (wire (pts (xy 27.178 34.29) (xy 29.21 34.29))
    (stroke (width 0) (type default))
  )
  (wire (pts (xy 258.445 152.4) (xy 247.65 152.4))
    (stroke (width 0) (type default))
  )
  (wire (pts (xy 195.58 241.935) (xy 195.58 245.11))
    (stroke (width 0) (type default))
  )
  (wire (pts (xy 231.14 241.935) (xy 233.68 241.935))
    (stroke (width 0) (type default))
  )
  (wire (pts (xy 251.46 193.04) (xy 253.365 193.04))
    (stroke (width 0) (type default))
  )
  (wire (pts (xy 219.71 118.11) (xy 218.44 118.11))
    (stroke (width 0) (type default))
  )
  (wire (pts (xy 236.855 152.4) (xy 236.855 154.94))
    (stroke (width 0) (type default))
  )
  (wire (pts (xy 108.585 141.605) (xy 94.615 141.605))
    (stroke (width 0) (type default))
  )
  (wire (pts (xy 251.46 191.77) (xy 251.46 193.04))
    (stroke (width 0) (type default))
  )
  (wire (pts (xy 73.025 239.395) (xy 90.17 239.395))
    (stroke (width 0) (type default))
  )
  (wire (pts (xy 360.68 66.04) (xy 360.68 69.85))
    (stroke (width 0) (type default))
  )
  (wire (pts (xy 382.27 66.04) (xy 386.08 66.04))
    (stroke (width 0) (type default))
  )
  (wire (pts (xy 94.615 38.1) (xy 97.155 38.1))
    (stroke (width 0) (type default))
  )
  (wire (pts (xy 125.73 93.345) (xy 125.73 106.045))
    (stroke (width 0) (type default))
  )
  (wire (pts (xy 196.85 162.56) (xy 196.85 163.83))
    (stroke (width 0) (type default))
  )
  (wire (pts (xy 212.725 241.935) (xy 226.06 241.935))
    (stroke (width 0) (type default))
  )
  (wire (pts (xy 196.85 44.45) (xy 198.12 44.45))
    (stroke (width 0) (type default))
  )
  (wire (pts (xy 307.34 41.275) (xy 307.34 34.29))
    (stroke (width 0) (type default))
  )
  (wire (pts (xy 231.14 193.04) (xy 229.235 193.04))
    (stroke (width 0) (type default))
  )
  (wire (pts (xy 44.45 93.345) (xy 45.72 93.345))
    (stroke (width 0) (type default))
  )
  (wire (pts (xy 104.14 262.255) (xy 125.095 262.255))
    (stroke (width 0) (type default))
  )
  (wire (pts (xy 125.095 264.795) (xy 125.095 262.255))
    (stroke (width 0) (type default))
  )
  (wire (pts (xy 235.585 34.29) (xy 236.855 34.29))
    (stroke (width 0) (type default))
  )
  (wire (pts (xy 218.44 82.55) (xy 236.855 82.55))
    (stroke (width 0) (type default))
  )
  (wire (pts (xy 342.265 39.37) (xy 341.63 39.37))
    (stroke (width 0) (type default))
  )
  (wire (pts (xy 86.995 149.225) (xy 89.535 149.225))
    (stroke (width 0) (type default))
  )
  (wire (pts (xy 170.18 198.12) (xy 170.18 77.47))
    (stroke (width 0) (type default))
  )
  (wire (pts (xy 175.26 241.935) (xy 187.325 241.935))
    (stroke (width 0) (type default))
  )
  (wire (pts (xy 236.855 34.29) (xy 247.65 34.29))
    (stroke (width 0) (type default))
  )
  (wire (pts (xy 74.295 93.345) (xy 85.09 93.345))
    (stroke (width 0) (type default))
  )
  (wire (pts (xy 44.45 41.91) (xy 57.15 41.91))
    (stroke (width 0) (type default))
  )
  (wire (pts (xy 218.44 72.39) (xy 229.235 72.39))
    (stroke (width 0) (type default))
  )
  (wire (pts (xy 146.05 241.935) (xy 134.62 241.935))
    (stroke (width 0) (type default))
  )
  (wire (pts (xy 196.85 123.19) (xy 196.85 124.46))
    (stroke (width 0) (type default))
  )
  (wire (pts (xy 258.445 193.04) (xy 260.35 193.04))
    (stroke (width 0) (type default))
  )
  (wire (pts (xy 218.44 193.04) (xy 229.235 193.04))
    (stroke (width 0) (type default))
  )
  (wire (pts (xy 229.235 157.48) (xy 229.235 152.4))
    (stroke (width 0) (type default))
  )
  (wire (pts (xy 360.68 76.2) (xy 360.68 80.01))
    (stroke (width 0) (type default))
  )
  (wire (pts (xy 248.92 34.29) (xy 258.445 34.29))
    (stroke (width 0) (type default))
  )
  (wire (pts (xy 370.84 66.04) (xy 382.27 66.04))
    (stroke (width 0) (type default))
  )
  (wire (pts (xy 104.14 250.825) (xy 125.095 250.825))
    (stroke (width 0) (type default))
  )
  (wire (pts (xy 44.45 38.1) (xy 44.45 34.29))
    (stroke (width 0) (type default))
  )
  (wire (pts (xy 33.02 36.195) (xy 33.02 34.29))
    (stroke (width 0) (type default))
  )
  (wire (pts (xy 230.505 34.29) (xy 229.235 34.29))
    (stroke (width 0) (type default))
  )
  (wire (pts (xy 88.9 41.91) (xy 97.155 41.91))
    (stroke (width 0) (type default))
  )
  (wire (pts (xy 33.655 94.615) (xy 33.655 89.535))
    (stroke (width 0) (type default))
  )
  (wire (pts (xy 256.54 259.715) (xy 267.335 259.715))
    (stroke (width 0) (type default))
  )
  (wire (pts (xy 254 241.935) (xy 267.97 241.935))
    (stroke (width 0) (type default))
  )
  (wire (pts (xy 44.45 34.29) (xy 57.15 34.29))
    (stroke (width 0) (type default))
  )
  (wire (pts (xy 48.26 108.585) (xy 54.61 108.585))
    (stroke (width 0) (type default))
  )
  (wire (pts (xy 29.21 55.88) (xy 33.02 55.88))
    (stroke (width 0) (type default))
  )
  (wire (pts (xy 173.99 157.48) (xy 173.99 118.11))
    (stroke (width 0) (type default))
  )
  (wire (pts (xy 107.95 50.8) (xy 107.95 38.1))
    (stroke (width 0) (type default))
  )
  (wire (pts (xy 88.9 48.26) (xy 88.9 49.53))
    (stroke (width 0) (type default))
  )
  (wire (pts (xy 95.885 97.155) (xy 95.885 98.425))
    (stroke (width 0) (type default))
  )
  (wire (pts (xy 118.11 93.345) (xy 118.11 92.075))
    (stroke (width 0) (type default))
  )
  (wire (pts (xy 243.205 71.12) (xy 243.205 72.39))
    (stroke (width 0) (type default))
  )
  (wire (pts (xy 218.44 162.56) (xy 236.855 162.56))
    (stroke (width 0) (type default))
  )
  (wire (pts (xy 274.955 241.935) (xy 274.955 245.11))
    (stroke (width 0) (type default))
  )
  (wire (pts (xy 258.445 152.4) (xy 258.445 165.1))
    (stroke (width 0) (type default))
  )
  (wire (pts (xy 81.28 41.91) (xy 86.36 41.91))
    (stroke (width 0) (type default))
  )
  (wire (pts (xy 33.655 89.535) (xy 44.45 89.535))
    (stroke (width 0) (type default))
  )
  (wire (pts (xy 248.92 34.29) (xy 248.92 45.72))
    (stroke (width 0) (type default))
  )
  (wire (pts (xy 74.93 41.91) (xy 76.2 41.91))
    (stroke (width 0) (type default))
  )
  (wire (pts (xy 184.15 113.03) (xy 198.12 113.03))
    (stroke (width 0) (type default))
  )
  (wire (pts (xy 320.04 44.45) (xy 320.04 46.355))
    (stroke (width 0) (type default))
  )
  (wire (pts (xy 154.305 241.935) (xy 154.305 244.475))
    (stroke (width 0) (type default))
  )
  (wire (pts (xy 86.995 141.605) (xy 86.995 149.225))
    (stroke (width 0) (type default))
  )
  (wire (pts (xy 48.26 49.53) (xy 48.26 45.72))
    (stroke (width 0) (type default))
  )
  (wire (pts (xy 196.85 123.19) (xy 198.12 123.19))
    (stroke (width 0) (type default))
  )
  (wire (pts (xy 177.8 113.03) (xy 184.15 113.03))
    (stroke (width 0) (type default))
  )
  (wire (pts (xy 177.8 152.4) (xy 184.15 152.4))
    (stroke (width 0) (type default))
  )
  (wire (pts (xy 238.125 193.04) (xy 238.125 195.58))
    (stroke (width 0) (type default))
  )
  (wire (pts (xy 50.165 38.1) (xy 57.15 38.1))
    (stroke (width 0) (type default))
  )
  (wire (pts (xy 320.04 76.2) (xy 320.04 77.47))
    (stroke (width 0) (type default))
  )
  (wire (pts (xy 243.205 72.39) (xy 247.65 72.39))
    (stroke (width 0) (type default))
  )
  (wire (pts (xy 118.11 93.345) (xy 125.73 93.345))
    (stroke (width 0) (type default))
  )
  (wire (pts (xy 353.695 34.29) (xy 352.425 34.29))
    (stroke (width 0) (type default))
  )
  (wire (pts (xy 104.14 245.11) (xy 125.095 245.11))
    (stroke (width 0) (type default))
  )
  (polyline (pts (xy 12.7 223.52) (xy 271.78 223.52))
    (stroke (width 0) (type default))
  )

  (wire (pts (xy 177.8 72.39) (xy 177.8 113.03))
    (stroke (width 0) (type default))
  )
  (wire (pts (xy 236.855 72.39) (xy 243.205 72.39))
    (stroke (width 0) (type default))
  )
  (wire (pts (xy 341.63 34.29) (xy 352.425 34.29))
    (stroke (width 0) (type default))
  )
  (wire (pts (xy 97.155 49.53) (xy 97.155 48.26))
    (stroke (width 0) (type default))
  )
  (wire (pts (xy 95.25 245.11) (xy 96.52 245.11))
    (stroke (width 0) (type default))
  )
  (wire (pts (xy 242.57 113.03) (xy 247.65 113.03))
    (stroke (width 0) (type default))
  )
  (wire (pts (xy 214.63 259.715) (xy 226.06 259.715))
    (stroke (width 0) (type default))
  )
  (wire (pts (xy 236.855 44.45) (xy 236.855 45.72))
    (stroke (width 0) (type default))
  )
  (wire (pts (xy 173.99 34.29) (xy 177.8 34.29))
    (stroke (width 0) (type default))
  )
  (wire (pts (xy 80.645 97.155) (xy 85.09 97.155))
    (stroke (width 0) (type default))
  )
  (wire (pts (xy 171.45 39.37) (xy 173.99 39.37))
    (stroke (width 0) (type default))
  )
  (wire (pts (xy 177.8 193.04) (xy 184.15 193.04))
    (stroke (width 0) (type default))
  )
  (wire (pts (xy 177.8 152.4) (xy 177.8 193.04))
    (stroke (width 0) (type default))
  )
  (wire (pts (xy 29.845 94.615) (xy 29.845 89.535))
    (stroke (width 0) (type default))
  )
  (wire (pts (xy 236.855 160.02) (xy 236.855 162.56))
    (stroke (width 0) (type default))
  )
  (wire (pts (xy 224.79 157.48) (xy 229.235 157.48))
    (stroke (width 0) (type default))
  )
  (wire (pts (xy 184.15 193.04) (xy 198.12 193.04))
    (stroke (width 0) (type default))
  )
  (wire (pts (xy 241.935 152.4) (xy 241.935 151.13))
    (stroke (width 0) (type default))
  )
  (polyline (pts (xy 280.035 12.7) (xy 280.035 223.52))
    (stroke (width 0) (type default))
  )

  (wire (pts (xy 88.9 43.18) (xy 88.9 41.91))
    (stroke (width 0) (type default))
  )
  (wire (pts (xy 236.22 193.04) (xy 238.125 193.04))
    (stroke (width 0) (type default))
  )
  (wire (pts (xy 224.79 198.12) (xy 229.235 198.12))
    (stroke (width 0) (type default))
  )
  (wire (pts (xy 44.45 54.61) (xy 44.45 55.88))
    (stroke (width 0) (type default))
  )
  (wire (pts (xy 134.62 93.345) (xy 135.89 93.345))
    (stroke (width 0) (type default))
  )
  (wire (pts (xy 268.605 113.03) (xy 266.065 113.03))
    (stroke (width 0) (type default))
  )
  (wire (pts (xy 86.995 97.155) (xy 95.885 97.155))
    (stroke (width 0) (type default))
  )
  (wire (pts (xy 55.245 49.53) (xy 55.245 55.88))
    (stroke (width 0) (type default))
  )
  (wire (pts (xy 198.12 198.12) (xy 170.18 198.12))
    (stroke (width 0) (type default))
  )
  (wire (pts (xy 229.235 118.11) (xy 229.235 113.03))
    (stroke (width 0) (type default))
  )
  (polyline (pts (xy 271.78 223.52) (xy 407.67 223.52))
    (stroke (width 0) (type default))
  )

  (wire (pts (xy 184.15 152.4) (xy 198.12 152.4))
    (stroke (width 0) (type default))
  )
  (wire (pts (xy 236.855 162.56) (xy 236.855 165.1))
    (stroke (width 0) (type default))
  )
  (wire (pts (xy 298.45 39.37) (xy 300.99 39.37))
    (stroke (width 0) (type default))
  )
  (wire (pts (xy 154.305 254.635) (xy 154.305 252.095))
    (stroke (width 0) (type default))
  )
  (wire (pts (xy 97.155 49.53) (xy 97.155 50.8))
    (stroke (width 0) (type default))
  )
  (wire (pts (xy 307.34 66.04) (xy 321.31 66.04))
    (stroke (width 0) (type default))
  )
  (wire (pts (xy 342.9 71.12) (xy 341.63 71.12))
    (stroke (width 0) (type default))
  )
  (wire (pts (xy 57.15 49.53) (xy 55.245 49.53))
    (stroke (width 0) (type default))
  )
  (wire (pts (xy 218.44 203.2) (xy 238.125 203.2))
    (stroke (width 0) (type default))
  )
  (wire (pts (xy 90.17 256.54) (xy 73.025 256.54))
    (stroke (width 0) (type default))
  )
  (wire (pts (xy 184.15 119.38) (xy 184.15 113.03))
    (stroke (width 0) (type default))
  )
  (wire (pts (xy 44.45 108.585) (xy 48.26 108.585))
    (stroke (width 0) (type default))
  )
  (wire (pts (xy 104.14 239.395) (xy 125.095 239.395))
    (stroke (width 0) (type default))
  )
  (wire (pts (xy 55.245 55.88) (xy 55.245 57.15))
    (stroke (width 0) (type default))
  )
  (wire (pts (xy 170.18 77.47) (xy 198.12 77.47))
    (stroke (width 0) (type default))
  )

  (text "SOM 5V" (at 13.97 19.05 0)
    (effects (font (size 2.54 2.54) (thickness 0.508) bold) (justify left bottom))
  )
  (text "Local FB" (at 112.395 141.605 0)
    (effects (font (size 1.27 1.27)) (justify left bottom))
  )
  (text "PL domain" (at 281.94 19.685 0)
    (effects (font (size 2.54 2.54) (thickness 0.508) bold) (justify left bottom))
  )
  (text "PS domain" (at 148.844 20.574 0)
    (effects (font (size 2.54 2.54) (thickness 0.508) bold) (justify left bottom))
  )
  (text "Remote FB" (at 112.395 149.86 0)
    (effects (font (size 1.27 1.27)) (justify left bottom))
  )
  (text "Power indication" (at 163.195 231.14 0)
    (effects (font (size 2.54 2.54) (thickness 0.508) bold) (justify left bottom))
  )

  (label "SOM_5V_OUT" (at 73.025 239.395 0) (fields_autoplaced)
    (effects (font (size 1 1)) (justify left bottom))
  )
  (label "SOM_5V_FB" (at 86.995 97.155 0) (fields_autoplaced)
    (effects (font (size 1.27 1.27)) (justify left bottom))
  )
  (label "SW_SOM_5V" (at 75.565 93.345 0) (fields_autoplaced)
    (effects (font (size 0.9906 0.9906)) (justify left bottom))
  )
  (label "USB_5V_OUT" (at 73.025 245.11 0) (fields_autoplaced)
    (effects (font (size 1 1)) (justify left bottom))
  )
  (label "SOM_5V_FB" (at 75.565 141.605 0) (fields_autoplaced)
    (effects (font (size 1.27 1.27)) (justify left bottom))
  )
  (label "PS_1V2_OUT" (at 248.285 152.4 0) (fields_autoplaced)
    (effects (font (size 1 1)) (justify left bottom))
  )
  (label "PS_2V5_OUT" (at 212.725 241.935 0) (fields_autoplaced)
    (effects (font (size 1 1)) (justify left bottom))
  )
  (label "PS_1V2_OUT" (at 176.53 259.715 0) (fields_autoplaced)
    (effects (font (size 1 1)) (justify left bottom))
  )
  (label "SW_PS_1V0" (at 219.71 193.04 0) (fields_autoplaced)
    (effects (font (size 0.9906 0.9906)) (justify left bottom))
  )
  (label "PS_3V3_OUT" (at 248.92 34.29 0) (fields_autoplaced)
    (effects (font (size 1 1)) (justify left bottom))
  )
  (label "SOM_5V_OUT" (at 96.52 93.345 0) (fields_autoplaced)
    (effects (font (size 1 1)) (justify left bottom))
  )
  (label "PS_1V0_OUT" (at 239.395 193.04 0) (fields_autoplaced)
    (effects (font (size 1 1)) (justify left bottom))
  )
  (label "SW_USB_5V" (at 76.2 38.1 0) (fields_autoplaced)
    (effects (font (size 0.9906 0.9906)) (justify left bottom))
  )
  (label "PS_1V0_OUT" (at 214.63 259.715 0) (fields_autoplaced)
    (effects (font (size 1 1)) (justify left bottom))
  )
  (label "PS_3V3_OUT" (at 73.025 250.825 0) (fields_autoplaced)
    (effects (font (size 1 1)) (justify left bottom))
  )
  (label "PS_3V3_OUT" (at 134.62 241.935 0) (fields_autoplaced)
    (effects (font (size 1 1)) (justify left bottom))
  )
  (label "PS_3V3_OUT" (at 175.26 241.935 0) (fields_autoplaced)
    (effects (font (size 1 1)) (justify left bottom))
  )
  (label "SOM_5V_OUT" (at 108.585 141.605 180) (fields_autoplaced)
    (effects (font (size 1 1)) (justify right bottom))
  )
  (label "SW_PS_1V2" (at 219.71 152.4 0) (fields_autoplaced)
    (effects (font (size 0.9906 0.9906)) (justify left bottom))
  )
  (label "PS_1V8_OUT" (at 248.285 113.03 0) (fields_autoplaced)
    (effects (font (size 1 1)) (justify left bottom))
  )
  (label "PL_3V3_OUT" (at 73.025 262.255 0) (fields_autoplaced)
    (effects (font (size 1 1)) (justify left bottom))
  )
  (label "PS_1V8_OUT" (at 135.509 259.715 0) (fields_autoplaced)
    (effects (font (size 1 1)) (justify left bottom))
  )
  (label "PL_3V3_OUT" (at 372.11 34.29 0) (fields_autoplaced)
    (effects (font (size 1 1)) (justify left bottom))
  )
  (label "PS_2V5_OUT" (at 73.025 256.54 0) (fields_autoplaced)
    (effects (font (size 1 1)) (justify left bottom))
  )
  (label "SW_PS_1V8" (at 219.71 113.03 0) (fields_autoplaced)
    (effects (font (size 0.9906 0.9906)) (justify left bottom))
  )
  (label "PL_1V2_OUT" (at 256.54 259.715 0) (fields_autoplaced)
    (effects (font (size 1 1)) (justify left bottom))
  )
  (label "SW_PS_2V5" (at 219.71 72.39 0) (fields_autoplaced)
    (effects (font (size 0.9906 0.9906)) (justify left bottom))
  )
  (label "PL_1V2_OUT" (at 372.11 66.04 0) (fields_autoplaced)
    (effects (font (size 1 1)) (justify left bottom))
  )
  (label "PS_2V5_OUT" (at 248.92 72.39 0) (fields_autoplaced)
    (effects (font (size 1 1)) (justify left bottom))
  )
  (label "SW_PS_3V3" (at 219.456 34.29 0) (fields_autoplaced)
    (effects (font (size 0.9906 0.9906)) (justify left bottom))
  )
  (label "SW_PL_3V3" (at 341.63 34.29 0) (fields_autoplaced)
    (effects (font (size 0.9906 0.9906)) (justify left bottom))
  )
  (label "PL_3V3_OUT" (at 254 241.935 0) (fields_autoplaced)
    (effects (font (size 1 1)) (justify left bottom))
  )
  (label "SW_PL_1V2" (at 342.9 66.04 0) (fields_autoplaced)
    (effects (font (size 0.9906 0.9906)) (justify left bottom))
  )
  (label "USB_5V_OUT" (at 97.79 38.1 0) (fields_autoplaced)
    (effects (font (size 1 1)) (justify left bottom))
  )

  (global_label "SOM_5V0" (shape input) (at 99.06 149.225 0) (fields_autoplaced)
    (effects (font (size 1.27 1.27)) (justify left))
    (property "Intersheetrefs" "${INTERSHEET_REFS}" (at 185.42 20.955 0)
      (effects (font (size 1.27 1.27)) hide)
    )
  )
  (global_label "PS_2V5" (shape input) (at 269.875 72.39 0) (fields_autoplaced)
    (effects (font (size 1.27 1.27)) (justify left))
    (property "Intersheetrefs" "${INTERSHEET_REFS}" (at 339.725 -168.91 0)
      (effects (font (size 1.27 1.27)) hide)
    )
  )
  (global_label "PS_1V8" (shape input) (at 268.605 113.03 0) (fields_autoplaced)
    (effects (font (size 1.27 1.27)) (justify left))
    (property "Intersheetrefs" "${INTERSHEET_REFS}" (at 379.095 -135.89 0)
      (effects (font (size 1.27 1.27)) hide)
    )
  )
  (global_label "PL_1V2" (shape input) (at 394.335 66.04 0) (fields_autoplaced)
    (effects (font (size 1.27 1.27)) (justify left))
    (property "Intersheetrefs" "${INTERSHEET_REFS}" (at 467.995 -316.23 0)
      (effects (font (size 1.27 1.27)) hide)
    )
  )
  (global_label "PS_1V0" (shape input) (at 260.35 193.04 0) (fields_autoplaced)
    (effects (font (size 1.27 1.27)) (justify left))
    (property "Intersheetrefs" "${INTERSHEET_REFS}" (at 450.85 -49.53 0)
      (effects (font (size 1.27 1.27)) hide)
    )
  )
  (global_label "PS_1V2" (shape input) (at 268.605 152.4 0) (fields_autoplaced)
    (effects (font (size 1.27 1.27)) (justify left))
    (property "Intersheetrefs" "${INTERSHEET_REFS}" (at 418.465 -96.52 0)
      (effects (font (size 1.27 1.27)) hide)
    )
  )
  (global_label "USB_5V" (shape input) (at 135.89 38.1 0) (fields_autoplaced)
    (effects (font (size 1.27 1.27)) (justify left))
    (property "Intersheetrefs" "${INTERSHEET_REFS}" (at 168.91 -91.44 0)
      (effects (font (size 1.27 1.27)) hide)
    )
  )
  (global_label "PL_3V3" (shape input) (at 395.605 34.29 0) (fields_autoplaced)
    (effects (font (size 1.27 1.27)) (justify left))
    (property "Intersheetrefs" "${INTERSHEET_REFS}" (at 427.355 -347.98 0)
      (effects (font (size 1.27 1.27)) hide)
    )
  )
  (global_label "PS_3V3" (shape input) (at 269.875 34.29 0) (fields_autoplaced)
    (effects (font (size 1.27 1.27)) (justify left))
    (property "Intersheetrefs" "${INTERSHEET_REFS}" (at 301.625 -214.63 0)
      (effects (font (size 1.27 1.27)) hide)
    )
  )
  (global_label "SOM_5V0" (shape input) (at 135.89 93.345 0) (fields_autoplaced)
    (effects (font (size 1.27 1.27)) (justify left))
    (property "Intersheetrefs" "${INTERSHEET_REFS}" (at 222.25 -34.925 0)
      (effects (font (size 1.27 1.27)) hide)
    )
  )

  (hierarchical_label "DC_MAIN_BUS" (shape input) (at 27.178 34.29 180) (fields_autoplaced)
    (effects (font (size 1.27 1.27)) (justify right))
  )
  (hierarchical_label "VCCOEN_PL_M2C" (shape input) (at 298.45 39.37 180) (fields_autoplaced)
    (effects (font (size 1.27 1.27)) (justify right))
  )
  (hierarchical_label "DC_MAIN_BUS" (shape input) (at 298.45 34.29 180) (fields_autoplaced)
    (effects (font (size 1.27 1.27)) (justify right))
  )
  (hierarchical_label "DC_MAIN_BUS" (shape input) (at 173.99 34.29 180) (fields_autoplaced)
    (effects (font (size 1.27 1.27)) (justify right))
  )
  (hierarchical_label "DC_MAIN_BUS" (shape input) (at 27.178 89.535 180) (fields_autoplaced)
    (effects (font (size 1.27 1.27)) (justify right))
  )
  (hierarchical_label "PS_ETH_EN" (shape input) (at 160.02 77.47 180) (fields_autoplaced)
    (effects (font (size 1.27 1.27)) (justify right))
  )
  (hierarchical_label "VCCOEN_PS_M2C" (shape input) (at 171.45 39.37 180) (fields_autoplaced)
    (effects (font (size 1.27 1.27)) (justify right))
  )

  (symbol (lib_id "kria-k26-devboard:LED_G_0603_LG_L29K-G2J1-24-Z") (at 96.52 239.395 0) (unit 1)
    (in_bom yes) (on_board yes) (dnp no)
    (property "Reference" "D12" (at 104.14 238.125 0)
      (effects (font (size 1.524 1.524)))
    )
    (property "Value" "LED_G_0603_LG_L29K-G2J1-24-Z" (at 102.2349 242.57 90)
      (effects (font (size 1.27 1.27) (thickness 0.15)) (justify right) hide)
    )
    (property "Footprint" "kria-k26-devboard-footprints:LED_0603_1608Metric_G" (at 101.6 234.315 0)
      (effects (font (size 1.27 1.27) (thickness 0.15)) (justify left bottom) hide)
    )
    (property "Datasheet" "https://dammedia.osram.info/media/resource/hires/osram-dam-2493945/LG%20L29K.pdf" (at 101.6 231.775 0)
      (effects (font (size 1.27 1.27) (thickness 0.15)) (justify left bottom) hide)
    )
    (property "MPN" "LG L29K-G2J1-24-Z" (at 102.235 240.665 0)
      (effects (font (size 1.27 1.27) (thickness 0.15)) (justify left) hide)
    )
    (property "Manufacturer" "OSRAM" (at 101.6 211.455 0)
      (effects (font (size 1.27 1.27) (thickness 0.15)) (justify left bottom) hide)
    )
    (property "Author" "Antmicro" (at 119.38 259.715 0)
      (effects (font (size 1.27 1.27) (thickness 0.15)) (justify left bottom) hide)
    )
    (property "License" "Apache-2.0" (at 119.38 262.255 0)
      (effects (font (size 1.27 1.27) (thickness 0.15)) (justify left bottom) hide)
    )
    (property "Color" "Green" (at 102.235 241.3 0)
      (effects (font (size 1.27 1.27)) (justify left bottom))
    )
    (pin "1")
    (pin "2")
    (instances
      (project "kria-k26-devboard"
        (path ""
          (reference "D12") (unit 1)
        )
      )
    )
  )

  (symbol (lib_id "kria-k26-devboard:LED_G_0603_LG_L29K-G2J1-24-Z") (at 96.52 250.825 0) (unit 1)
    (in_bom yes) (on_board yes) (dnp no)
    (property "Reference" "D14" (at 104.14 249.555 0)
      (effects (font (size 1.524 1.524)))
    )
    (property "Value" "LED_G_0603_LG_L29K-G2J1-24-Z" (at 102.2349 247.65 90)
      (effects (font (size 1.27 1.27) (thickness 0.15)) (justify left) hide)
    )
    (property "Footprint" "kria-k26-devboard-footprints:LED_0603_1608Metric_G" (at 101.6 245.745 0)
      (effects (font (size 1.27 1.27) (thickness 0.15)) (justify left bottom) hide)
    )
    (property "Datasheet" "https://dammedia.osram.info/media/resource/hires/osram-dam-2493945/LG%20L29K.pdf" (at 101.6 243.205 0)
      (effects (font (size 1.27 1.27) (thickness 0.15)) (justify left bottom) hide)
    )
    (property "MPN" "LG L29K-G2J1-24-Z" (at 102.235 252.095 0)
      (effects (font (size 1.27 1.27) (thickness 0.15)) (justify left) hide)
    )
    (property "Manufacturer" "OSRAM" (at 101.6 222.885 0)
      (effects (font (size 1.27 1.27) (thickness 0.15)) (justify left bottom) hide)
    )
    (property "Author" "Antmicro" (at 119.38 271.145 0)
      (effects (font (size 1.27 1.27) (thickness 0.15)) (justify left bottom) hide)
    )
    (property "License" "Apache-2.0" (at 119.38 273.685 0)
      (effects (font (size 1.27 1.27) (thickness 0.15)) (justify left bottom) hide)
    )
    (property "Color" "Green" (at 102.235 252.73 0)
      (effects (font (size 1.27 1.27)) (justify left bottom))
    )
    (pin "1")
    (pin "2")
    (instances
      (project "kria-k26-devboard"
        (path ""
          (reference "D14") (unit 1)
        )
      )
    )
  )

  (symbol (lib_id "kria-k26-devboard:R_1k_0402") (at 90.17 250.825 0) (unit 1)
    (in_bom yes) (on_board yes) (dnp no)
    (property "Reference" "R126" (at 87.63 249.555 0)
      (effects (font (size 1.524 1.524)))
    )
    (property "Value" "R_1k_0402" (at 90.17 254.635 0)
      (effects (font (size 1.27 1.27) (thickness 0.15)) (justify left bottom) hide)
    )
    (property "Footprint" "kria-k26-devboard-footprints:R_0402_1005Metric" (at 95.25 245.745 0)
      (effects (font (size 1.27 1.27) (thickness 0.15)) (justify left bottom) hide)
    )
    (property "Datasheet" "https://www.bourns.com/docs/product-datasheets/cr.pdf" (at 90.17 250.825 0)
      (effects (font (size 1.27 1.27) (thickness 0.15)) (justify left bottom) hide)
    )
    (property "Manufacturer" "Bourns" (at 95.25 240.665 0)
      (effects (font (size 1.27 1.27) (thickness 0.15)) (justify left bottom) hide)
    )
    (property "MPN" "CR0402-FX-1001GLF" (at 95.25 243.205 0)
      (effects (font (size 1.27 1.27) (thickness 0.15)) (justify left bottom) hide)
    )
    (property "Val" "1k" (at 87.63 252.095 0)
      (effects (font (size 1.27 1.27) (thickness 0.15)))
    )
    (property "License" "Apache-2.0" (at 110.49 276.225 0)
      (effects (font (size 1.27 1.27) (thickness 0.15)) (justify left bottom) hide)
    )
    (property "Author" "Antmicro" (at 110.49 278.765 0)
      (effects (font (size 1.27 1.27) (thickness 0.15)) (justify left bottom) hide)
    )
    (property "Tolerance" "1%" (at 110.49 260.985 0)
      (effects (font (size 1.27 1.27)) (justify left bottom) hide)
    )
    (pin "1")
    (pin "2")
    (instances
      (project "kria-k26-devboard"
        (path ""
          (reference "R126") (unit 1)
        )
      )
    )
  )

  (symbol (lib_id "kria-k26-devboard:LED_G_0603_LG_L29K-G2J1-24-Z") (at 96.52 256.54 0) (unit 1)
    (in_bom yes) (on_board yes) (dnp no)
    (property "Reference" "D15" (at 104.14 255.27 0)
      (effects (font (size 1.524 1.524)))
    )
    (property "Value" "LED_G_0603_LG_L29K-G2J1-24-Z" (at 102.2349 252.73 90)
      (effects (font (size 1.27 1.27) (thickness 0.15)) (justify left) hide)
    )
    (property "Footprint" "kria-k26-devboard-footprints:LED_0603_1608Metric_G" (at 101.6 251.46 0)
      (effects (font (size 1.27 1.27) (thickness 0.15)) (justify left bottom) hide)
    )
    (property "Datasheet" "https://dammedia.osram.info/media/resource/hires/osram-dam-2493945/LG%20L29K.pdf" (at 101.6 248.92 0)
      (effects (font (size 1.27 1.27) (thickness 0.15)) (justify left bottom) hide)
    )
    (property "MPN" "LG L29K-G2J1-24-Z" (at 102.235 257.81 0)
      (effects (font (size 1.27 1.27) (thickness 0.15)) (justify left) hide)
    )
    (property "Manufacturer" "OSRAM" (at 101.6 228.6 0)
      (effects (font (size 1.27 1.27) (thickness 0.15)) (justify left bottom) hide)
    )
    (property "Author" "Antmicro" (at 119.38 276.86 0)
      (effects (font (size 1.27 1.27) (thickness 0.15)) (justify left bottom) hide)
    )
    (property "License" "Apache-2.0" (at 119.38 279.4 0)
      (effects (font (size 1.27 1.27) (thickness 0.15)) (justify left bottom) hide)
    )
    (property "Color" "Green" (at 102.235 258.445 0)
      (effects (font (size 1.27 1.27)) (justify left bottom))
    )
    (pin "1")
    (pin "2")
    (instances
      (project "kria-k26-devboard"
        (path ""
          (reference "D15") (unit 1)
        )
      )
    )
  )

  (symbol (lib_id "kria-k26-devboard:LED_G_0603_LG_L29K-G2J1-24-Z") (at 154.305 244.475 270) (unit 1)
    (in_bom yes) (on_board yes) (dnp no) (fields_autoplaced)
    (property "Reference" "D16" (at 157.48 247.015 90)
      (effects (font (size 1.524 1.524)) (justify left))
    )
    (property "Value" "LED_G_0603_LG_L29K-G2J1-24-Z" (at 157.48 250.1899 90)
      (effects (font (size 1.27 1.27) (thickness 0.15)) (justify left) hide)
    )
    (property "Footprint" "kria-k26-devboard-footprints:LED_0603_1608Metric_G" (at 159.385 249.555 0)
      (effects (font (size 1.27 1.27) (thickness 0.15)) (justify left bottom) hide)
    )
    (property "Datasheet" "https://dammedia.osram.info/media/resource/hires/osram-dam-2493945/LG%20L29K.pdf" (at 161.925 249.555 0)
      (effects (font (size 1.27 1.27) (thickness 0.15)) (justify left bottom) hide)
    )
    (property "MPN" "LG L29K-G2J1-24-Z" (at 157.48 250.1899 90)
      (effects (font (size 1.27 1.27) (thickness 0.15)) (justify left) hide)
    )
    (property "Manufacturer" "OSRAM" (at 182.245 249.555 0)
      (effects (font (size 1.27 1.27) (thickness 0.15)) (justify left bottom) hide)
    )
    (property "Author" "Antmicro" (at 133.985 267.335 0)
      (effects (font (size 1.27 1.27) (thickness 0.15)) (justify left bottom) hide)
    )
    (property "License" "Apache-2.0" (at 131.445 267.335 0)
      (effects (font (size 1.27 1.27) (thickness 0.15)) (justify left bottom) hide)
    )
    (property "Color" "Green" (at 149.225 264.795 0)
      (effects (font (size 1.27 1.27)) (justify left bottom))
    )
    (pin "1")
    (pin "2")
    (instances
      (project "kria-k26-devboard"
        (path ""
          (reference "D16") (unit 1)
        )
      )
    )
  )

  (symbol (lib_id "kria-k26-devboard:GND") (at 154.305 264.795 0) (unit 1)
    (in_bom yes) (on_board yes) (dnp no) (fields_autoplaced)
    (property "Reference" "#PWR0374" (at 154.305 271.145 0)
      (effects (font (size 1.27 1.27)) hide)
    )
    (property "Value" "GND" (at 154.305 269.875 0)
      (effects (font (size 1.27 1.27)))
    )
    (property "Footprint" "" (at 163.195 272.415 0)
      (effects (font (size 1.27 1.27) (thickness 0.15)) (justify left bottom) hide)
    )
    (property "Datasheet" "" (at 163.195 277.495 0)
      (effects (font (size 1.27 1.27) (thickness 0.15)) (justify left bottom) hide)
    )
    (property "Author" "Antmicro" (at 163.195 272.415 0)
      (effects (font (size 1.27 1.27) (thickness 0.15)) (justify left bottom) hide)
    )
    (property "License" "Apache-2.0" (at 163.195 274.955 0)
      (effects (font (size 1.27 1.27) (thickness 0.15)) (justify left bottom) hide)
    )
    (pin "1")
    (instances
      (project "kria-k26-devboard"
        (path ""
          (reference "#PWR0374") (unit 1)
        )
      )
    )
  )

  (symbol (lib_id "kria-k26-devboard:R_510R_0402") (at 95.25 256.54 180) (unit 1)
    (in_bom yes) (on_board yes) (dnp no)
    (property "Reference" "R128" (at 87.63 255.27 0)
      (effects (font (size 1.524 1.524)))
    )
    (property "Value" "R_510R_0402" (at 95.25 252.73 0)
      (effects (font (size 1.27 1.27) (thickness 0.15)) (justify left bottom) hide)
    )
    (property "Footprint" "kria-k26-devboard-footprints:R_0402_1005Metric" (at 90.17 261.62 0)
      (effects (font (size 1.27 1.27) (thickness 0.15)) (justify left bottom) hide)
    )
    (property "Datasheet" "https://www.bourns.com/docs/product-datasheets/cr.pdf" (at 95.25 256.54 0)
      (effects (font (size 1.27 1.27) (thickness 0.15)) (justify left bottom) hide)
    )
    (property "Manufacturer" "Bourns" (at 90.17 266.7 0)
      (effects (font (size 1.27 1.27) (thickness 0.15)) (justify left bottom) hide)
    )
    (property "MPN" "CR0402-FX-5100GLF" (at 90.17 264.16 0)
      (effects (font (size 1.27 1.27) (thickness 0.15)) (justify left bottom) hide)
    )
    (property "Val" "510R" (at 87.63 257.81 0)
      (effects (font (size 1.27 1.27) (thickness 0.15)))
    )
    (property "License" "Apache-2.0" (at 74.93 231.14 0)
      (effects (font (size 1.27 1.27) (thickness 0.15)) (justify left bottom) hide)
    )
    (property "Author" "Antmicro" (at 74.93 228.6 0)
      (effects (font (size 1.27 1.27) (thickness 0.15)) (justify left bottom) hide)
    )
    (property "Tolerance" "1%" (at 74.93 246.38 0)
      (effects (font (size 1.27 1.27)) (justify left bottom) hide)
    )
    (pin "1")
    (pin "2")
    (instances
      (project "kria-k26-devboard"
        (path ""
          (reference "R128") (unit 1)
        )
      )
    )
  )

  (symbol (lib_id "kria-k26-devboard:AP62301_TSOT") (at 198.12 34.29 0) (unit 1)
    (in_bom yes) (on_board yes) (dnp no) (fields_autoplaced)
    (property "Reference" "U49" (at 208.28 26.67 0)
      (effects (font (size 1.27 1.27)))
    )
    (property "Value" "AP62301_TSOT" (at 208.28 29.21 0)
      (effects (font (size 1.27 1.27)))
    )
    (property "Footprint" "kria-k26-devboard-footprints:TSOT23-6" (at 196.85 50.8 0)
      (effects (font (size 1.27 1.27) (thickness 0.15)) (justify left bottom) hide)
    )
    (property "Datasheet" "https://www.diodes.com/assets/Datasheets/AP62300_AP62301_AP62300T.pdf" (at 196.85 43.18 0)
      (effects (font (size 1.27 1.27) (thickness 0.15)) (justify left bottom) hide)
    )
    (property "MPN" "AP62301WU-7" (at 196.85 48.26 0)
      (effects (font (size 1.27 1.27) (thickness 0.15)) (justify left bottom) hide)
    )
    (property "Manufacturer" "Diodes Incorporated" (at 196.85 45.72 0)
      (effects (font (size 1.27 1.27) (thickness 0.15)) (justify left bottom) hide)
    )
    (property "Author" "Antmicro" (at 233.68 41.91 0)
      (effects (font (size 1.27 1.27) (thickness 0.15)) (justify left bottom) hide)
    )
    (property "License" "Apache-2.0" (at 233.68 44.45 0)
      (effects (font (size 1.27 1.27) (thickness 0.15)) (justify left bottom) hide)
    )
    (pin "1")
    (pin "2")
    (pin "3")
    (pin "4")
    (pin "5")
    (pin "6")
    (instances
      (project "kria-k26-devboard"
        (path ""
          (reference "U49") (unit 1)
        )
      )
    )
  )

  (symbol (lib_id "kria-k26-devboard:L_2u2_7.8A_Coilcraft-XEL4030") (at 230.505 34.29 0) (unit 1)
    (in_bom yes) (on_board yes) (dnp no) (fields_autoplaced)
    (property "Reference" "L3" (at 233.045 29.21 0)
      (effects (font (size 1.27 1.27)))
    )
    (property "Value" "L_2u2_6.1A_XEL4030" (at 233.045 29.21 0)
      (effects (font (size 1.27 1.27)) hide)
    )
    (property "Footprint" "kria-k26-devboard-footprints:L_Coilcraft-XEL4030" (at 250.825 27.94 0)
      (effects (font (size 1.27 1.27) (thickness 0.15)) (justify left bottom) hide)
    )
    (property "Datasheet" "https://www.coilcraft.com/getmedia/8245f050-f190-4295-8c41-7c03d662ee3d/xel4030.pdf" (at 231.902 33.528 0)
      (effects (font (size 1.27 1.27) (thickness 0.15)) (justify left bottom) hide)
    )
    (property "MPN" "XEL4030-222MEC" (at 235.585 21.59 0)
      (effects (font (size 1.27 1.27) (thickness 0.15)) (justify left bottom) hide)
    )
    (property "Manufacturer" "Coilcraft" (at 238.125 19.05 0)
      (effects (font (size 1.27 1.27) (thickness 0.15)) (justify left bottom) hide)
    )
    (property "Val" "2u2/6.1A" (at 233.045 31.75 0)
      (effects (font (size 1.27 1.27) (thickness 0.15)))
    )
    (property "Size" "4x4" (at 233.68 26.035 0)
      (effects (font (size 1.27 1.27) (thickness 0.15)) (justify left bottom) hide)
    )
    (property "ISat" "" (at 244.475 50.8 0)
      (effects (font (size 1.27 1.27)) (justify left) hide)
    )
    (property "IMax" "" (at 244.475 54.61 0)
      (effects (font (size 1.27 1.27) (thickness 0.15)) (justify left bottom) hide)
    )
    (property "Author" "Antmicro" (at 244.475 59.69 0)
      (effects (font (size 1.27 1.27) (thickness 0.15)) (justify left bottom) hide)
    )
    (property "License" "Apache-2.0" (at 244.475 62.23 0)
      (effects (font (size 1.27 1.27) (thickness 0.15)) (justify left bottom) hide)
    )
    (pin "1")
    (pin "2")
    (instances
      (project "kria-k26-devboard"
        (path ""
          (reference "L3") (unit 1)
        )
      )
    )
  )

  (symbol (lib_id "kria-k26-devboard:C_100n_0402") (at 219.71 39.37 0) (unit 1)
    (in_bom yes) (on_board yes) (dnp no)
    (property "Reference" "C206" (at 226.06 38.1 0)
      (effects (font (size 1.524 1.524)))
    )
    (property "Value" "C_100n_0402" (at 219.71 43.18 0)
      (effects (font (size 1.524 1.524)) hide)
    )
    (property "Footprint" "kria-k26-devboard-footprints:C_0402_1005Metric" (at 224.79 34.29 0)
      (effects (font (size 1.27 1.27) (thickness 0.15)) (justify left bottom) hide)
    )
    (property "Datasheet" "https://search.murata.co.jp/Ceramy/image/img/A01X/G101/ENG/GRM155R61H104KE14-01.pdf" (at 219.71 39.37 0)
      (effects (font (size 1.27 1.27) (thickness 0.15)) (justify left bottom) hide)
    )
    (property "Manufacturer" "Murata" (at 224.79 29.21 0)
      (effects (font (size 1.27 1.27) (thickness 0.15)) (justify left bottom) hide)
    )
    (property "MPN" "GRM155R61H104KE14D" (at 224.79 31.75 0)
      (effects (font (size 1.27 1.27) (thickness 0.15)) (justify left bottom) hide)
    )
    (property "Val" "100n" (at 226.06 40.64 0)
      (effects (font (size 1.27 1.27) (thickness 0.15)))
    )
    (property "License" "Apache-2.0" (at 240.03 62.23 0)
      (effects (font (size 1.27 1.27) (thickness 0.15)) (justify left bottom) hide)
    )
    (property "Author" "Antmicro" (at 240.03 64.77 0)
      (effects (font (size 1.27 1.27) (thickness 0.15)) (justify left bottom) hide)
    )
    (property "Voltage" "50V" (at 240.03 67.31 0)
      (effects (font (size 1.27 1.27)) (justify left bottom) hide)
    )
    (property "Dielectric" "X5R" (at 240.03 69.85 0)
      (effects (font (size 1.27 1.27)) (justify left bottom) hide)
    )
    (pin "1")
    (pin "2")
    (instances
      (project "kria-k26-devboard"
        (path ""
          (reference "C206") (unit 1)
        )
      )
    )
  )

  (symbol (lib_id "kria-k26-devboard:C_22u_0603") (at 258.445 45.72 270) (unit 1)
    (in_bom yes) (on_board yes) (dnp no)
    (property "Reference" "C216" (at 259.08 46.355 90)
      (effects (font (size 1.524 1.524)) (justify left))
    )
    (property "Value" "C_22u_0603" (at 254.635 45.72 0)
      (effects (font (size 1.524 1.524)) hide)
    )
    (property "Footprint" "kria-k26-devboard-footprints:C_0603_1608Metric" (at 263.525 50.8 0)
      (effects (font (size 1.27 1.27) (thickness 0.15)) (justify left bottom) hide)
    )
    (property "Datasheet" " " (at 258.445 45.72 0)
      (effects (font (size 1.27 1.27) (thickness 0.15)) (justify left bottom) hide)
    )
    (property "Manufacturer" "Murata" (at 268.605 50.8 0)
      (effects (font (size 1.27 1.27) (thickness 0.15)) (justify left bottom) hide)
    )
    (property "MPN" "GRM188R60J226MEA0D" (at 266.065 50.8 0)
      (effects (font (size 1.27 1.27) (thickness 0.15)) (justify left bottom) hide)
    )
    (property "Val" "22u" (at 259.08 50.165 90)
      (effects (font (size 1.27 1.27) (thickness 0.15)) (justify left))
    )
    (property "License" "Apache-2.0" (at 235.585 66.04 0)
      (effects (font (size 1.27 1.27) (thickness 0.15)) (justify left bottom) hide)
    )
    (property "Author" "Antmicro" (at 233.045 66.04 0)
      (effects (font (size 1.27 1.27) (thickness 0.15)) (justify left bottom) hide)
    )
    (property "Voltage" "" (at 230.505 66.04 0)
      (effects (font (size 1.27 1.27)) (justify left bottom) hide)
    )
    (property "Dielectric" "" (at 227.965 66.04 0)
      (effects (font (size 1.27 1.27)) (justify left bottom) hide)
    )
    (pin "1")
    (pin "2")
    (instances
      (project "kria-k26-devboard"
        (path ""
          (reference "C216") (unit 1)
        )
      )
    )
  )

  (symbol (lib_id "kria-k26-devboard:C_22u_0603") (at 248.92 45.72 270) (unit 1)
    (in_bom yes) (on_board yes) (dnp no)
    (property "Reference" "C211" (at 249.555 46.355 90)
      (effects (font (size 1.524 1.524)) (justify left))
    )
    (property "Value" "C_22u_0603" (at 245.11 45.72 0)
      (effects (font (size 1.524 1.524)) hide)
    )
    (property "Footprint" "kria-k26-devboard-footprints:C_0603_1608Metric" (at 254 50.8 0)
      (effects (font (size 1.27 1.27) (thickness 0.15)) (justify left bottom) hide)
    )
    (property "Datasheet" " " (at 248.92 45.72 0)
      (effects (font (size 1.27 1.27) (thickness 0.15)) (justify left bottom) hide)
    )
    (property "Manufacturer" "Murata" (at 259.08 50.8 0)
      (effects (font (size 1.27 1.27) (thickness 0.15)) (justify left bottom) hide)
    )
    (property "MPN" "GRM188R60J226MEA0D" (at 256.54 50.8 0)
      (effects (font (size 1.27 1.27) (thickness 0.15)) (justify left bottom) hide)
    )
    (property "Val" "22u" (at 249.555 50.165 90)
      (effects (font (size 1.27 1.27) (thickness 0.15)) (justify left))
    )
    (property "License" "Apache-2.0" (at 226.06 66.04 0)
      (effects (font (size 1.27 1.27) (thickness 0.15)) (justify left bottom) hide)
    )
    (property "Author" "Antmicro" (at 223.52 66.04 0)
      (effects (font (size 1.27 1.27) (thickness 0.15)) (justify left bottom) hide)
    )
    (property "Voltage" "" (at 220.98 66.04 0)
      (effects (font (size 1.27 1.27)) (justify left bottom) hide)
    )
    (property "Dielectric" "" (at 218.44 66.04 0)
      (effects (font (size 1.27 1.27)) (justify left bottom) hide)
    )
    (pin "1")
    (pin "2")
    (instances
      (project "kria-k26-devboard"
        (path ""
          (reference "C211") (unit 1)
        )
      )
    )
  )

  (symbol (lib_id "kria-k26-devboard:R_31k6_0402") (at 236.855 38.1 270) (unit 1)
    (in_bom yes) (on_board yes) (dnp no) (fields_autoplaced)
    (property "Reference" "R131" (at 239.395 39.37 90)
      (effects (font (size 1.524 1.524)) (justify left))
    )
    (property "Value" "R_31k6_0402" (at 233.045 38.1 0)
      (effects (font (size 1.524 1.524)) hide)
    )
    (property "Footprint" "kria-k26-devboard-footprints:R_0402_1005Metric" (at 241.935 43.18 0)
      (effects (font (size 1.27 1.27) (thickness 0.15)) (justify left bottom) hide)
    )
    (property "Datasheet" "https://www.bourns.com/docs/product-datasheets/cr.pdf" (at 236.855 38.1 0)
      (effects (font (size 1.27 1.27) (thickness 0.15)) (justify left bottom) hide)
    )
    (property "Manufacturer" "Bourns" (at 247.015 43.18 0)
      (effects (font (size 1.27 1.27) (thickness 0.15)) (justify left bottom) hide)
    )
    (property "MPN" "CR0402-FX-3162GLF" (at 244.475 43.18 0)
      (effects (font (size 1.27 1.27) (thickness 0.15)) (justify left bottom) hide)
    )
    (property "Val" "31k6" (at 239.395 42.5449 90)
      (effects (font (size 1.27 1.27) (thickness 0.15)) (justify left))
    )
    (property "License" "Apache-2.0" (at 211.455 58.42 0)
      (effects (font (size 1.27 1.27) (thickness 0.15)) (justify left bottom) hide)
    )
    (property "Author" "Antmicro" (at 208.915 58.42 0)
      (effects (font (size 1.27 1.27) (thickness 0.15)) (justify left bottom) hide)
    )
    (property "Tolerance" "1%" (at 226.695 58.42 0)
      (effects (font (size 1.27 1.27)) (justify left bottom) hide)
    )
    (pin "1")
    (pin "2")
    (instances
      (project "kria-k26-devboard"
        (path ""
          (reference "R131") (unit 1)
        )
      )
    )
  )

  (symbol (lib_id "kria-k26-devboard:GND") (at 184.15 45.72 0) (unit 1)
    (in_bom yes) (on_board yes) (dnp no) (fields_autoplaced)
    (property "Reference" "#PWR0369" (at 184.15 52.07 0)
      (effects (font (size 1.27 1.27)) hide)
    )
    (property "Value" "GND" (at 184.15 50.8 0)
      (effects (font (size 1.27 1.27)))
    )
    (property "Footprint" "" (at 193.04 53.34 0)
      (effects (font (size 1.27 1.27) (thickness 0.15)) (justify left bottom) hide)
    )
    (property "Datasheet" "" (at 193.04 58.42 0)
      (effects (font (size 1.27 1.27) (thickness 0.15)) (justify left bottom) hide)
    )
    (property "Author" "Antmicro" (at 193.04 53.34 0)
      (effects (font (size 1.27 1.27) (thickness 0.15)) (justify left bottom) hide)
    )
    (property "License" "Apache-2.0" (at 193.04 55.88 0)
      (effects (font (size 1.27 1.27) (thickness 0.15)) (justify left bottom) hide)
    )
    (pin "1")
    (instances
      (project "kria-k26-devboard"
        (path ""
          (reference "#PWR0369") (unit 1)
        )
      )
    )
  )

  (symbol (lib_id "kria-k26-devboard:AP62301_TSOT") (at 198.12 72.39 0) (unit 1)
    (in_bom yes) (on_board yes) (dnp no) (fields_autoplaced)
    (property "Reference" "U50" (at 208.28 64.77 0)
      (effects (font (size 1.27 1.27)))
    )
    (property "Value" "AP62301_TSOT" (at 208.28 67.31 0)
      (effects (font (size 1.27 1.27)))
    )
    (property "Footprint" "kria-k26-devboard-footprints:TSOT23-6" (at 196.85 88.9 0)
      (effects (font (size 1.27 1.27) (thickness 0.15)) (justify left bottom) hide)
    )
    (property "Datasheet" "https://www.diodes.com/assets/Datasheets/AP62300_AP62301_AP62300T.pdf" (at 196.85 81.28 0)
      (effects (font (size 1.27 1.27) (thickness 0.15)) (justify left bottom) hide)
    )
    (property "MPN" "AP62301WU-7" (at 196.85 86.36 0)
      (effects (font (size 1.27 1.27) (thickness 0.15)) (justify left bottom) hide)
    )
    (property "Manufacturer" "Diodes Incorporated" (at 196.85 83.82 0)
      (effects (font (size 1.27 1.27) (thickness 0.15)) (justify left bottom) hide)
    )
    (property "Author" "Antmicro" (at 233.68 80.01 0)
      (effects (font (size 1.27 1.27) (thickness 0.15)) (justify left bottom) hide)
    )
    (property "License" "Apache-2.0" (at 233.68 82.55 0)
      (effects (font (size 1.27 1.27) (thickness 0.15)) (justify left bottom) hide)
    )
    (pin "1")
    (pin "2")
    (pin "3")
    (pin "4")
    (pin "5")
    (pin "6")
    (instances
      (project "kria-k26-devboard"
        (path ""
          (reference "U50") (unit 1)
        )
      )
    )
  )

  (symbol (lib_id "kria-k26-devboard:C_100n_0402") (at 219.71 77.47 0) (unit 1)
    (in_bom yes) (on_board yes) (dnp no)
    (property "Reference" "C207" (at 226.06 76.2 0)
      (effects (font (size 1.524 1.524)))
    )
    (property "Value" "C_100n_0402" (at 219.71 81.28 0)
      (effects (font (size 1.524 1.524)) hide)
    )
    (property "Footprint" "kria-k26-devboard-footprints:C_0402_1005Metric" (at 224.79 72.39 0)
      (effects (font (size 1.27 1.27) (thickness 0.15)) (justify left bottom) hide)
    )
    (property "Datasheet" "https://search.murata.co.jp/Ceramy/image/img/A01X/G101/ENG/GRM155R61H104KE14-01.pdf" (at 219.71 77.47 0)
      (effects (font (size 1.27 1.27) (thickness 0.15)) (justify left bottom) hide)
    )
    (property "Manufacturer" "Murata" (at 224.79 67.31 0)
      (effects (font (size 1.27 1.27) (thickness 0.15)) (justify left bottom) hide)
    )
    (property "MPN" "GRM155R61H104KE14D" (at 224.79 69.85 0)
      (effects (font (size 1.27 1.27) (thickness 0.15)) (justify left bottom) hide)
    )
    (property "Val" "100n" (at 226.06 78.74 0)
      (effects (font (size 1.27 1.27) (thickness 0.15)))
    )
    (property "License" "Apache-2.0" (at 240.03 100.33 0)
      (effects (font (size 1.27 1.27) (thickness 0.15)) (justify left bottom) hide)
    )
    (property "Author" "Antmicro" (at 240.03 102.87 0)
      (effects (font (size 1.27 1.27) (thickness 0.15)) (justify left bottom) hide)
    )
    (property "Voltage" "50V" (at 240.03 105.41 0)
      (effects (font (size 1.27 1.27)) (justify left bottom) hide)
    )
    (property "Dielectric" "X5R" (at 240.03 107.95 0)
      (effects (font (size 1.27 1.27)) (justify left bottom) hide)
    )
    (pin "1")
    (pin "2")
    (instances
      (project "kria-k26-devboard"
        (path ""
          (reference "C207") (unit 1)
        )
      )
    )
  )

  (symbol (lib_id "kria-k26-devboard:C_22u_0603") (at 247.65 83.82 270) (unit 1)
    (in_bom yes) (on_board yes) (dnp no) (fields_autoplaced)
    (property "Reference" "C212" (at 250.825 85.0963 90)
      (effects (font (size 1.524 1.524)) (justify left))
    )
    (property "Value" "C_22u_0603" (at 243.84 83.82 0)
      (effects (font (size 1.524 1.524)) hide)
    )
    (property "Footprint" "kria-k26-devboard-footprints:C_0603_1608Metric" (at 252.73 88.9 0)
      (effects (font (size 1.27 1.27) (thickness 0.15)) (justify left bottom) hide)
    )
    (property "Datasheet" " " (at 247.65 83.82 0)
      (effects (font (size 1.27 1.27) (thickness 0.15)) (justify left bottom) hide)
    )
    (property "Manufacturer" "Murata" (at 257.81 88.9 0)
      (effects (font (size 1.27 1.27) (thickness 0.15)) (justify left bottom) hide)
    )
    (property "MPN" "GRM188R60J226MEA0D" (at 255.27 88.9 0)
      (effects (font (size 1.27 1.27) (thickness 0.15)) (justify left bottom) hide)
    )
    (property "Val" "22u" (at 250.825 88.2712 90)
      (effects (font (size 1.27 1.27) (thickness 0.15)) (justify left))
    )
    (property "License" "Apache-2.0" (at 224.79 104.14 0)
      (effects (font (size 1.27 1.27) (thickness 0.15)) (justify left bottom) hide)
    )
    (property "Author" "Antmicro" (at 222.25 104.14 0)
      (effects (font (size 1.27 1.27) (thickness 0.15)) (justify left bottom) hide)
    )
    (property "Voltage" "" (at 219.71 104.14 0)
      (effects (font (size 1.27 1.27)) (justify left bottom) hide)
    )
    (property "Dielectric" "" (at 217.17 104.14 0)
      (effects (font (size 1.27 1.27)) (justify left bottom) hide)
    )
    (pin "1")
    (pin "2")
    (instances
      (project "kria-k26-devboard"
        (path ""
          (reference "C212") (unit 1)
        )
      )
    )
  )

  (symbol (lib_id "kria-k26-devboard:GND") (at 196.85 83.82 0) (unit 1)
    (in_bom yes) (on_board yes) (dnp no) (fields_autoplaced)
    (property "Reference" "#PWR0370" (at 196.85 90.17 0)
      (effects (font (size 1.27 1.27)) hide)
    )
    (property "Value" "GND" (at 196.85 88.9 0)
      (effects (font (size 1.27 1.27)))
    )
    (property "Footprint" "" (at 205.74 91.44 0)
      (effects (font (size 1.27 1.27) (thickness 0.15)) (justify left bottom) hide)
    )
    (property "Datasheet" "" (at 205.74 96.52 0)
      (effects (font (size 1.27 1.27) (thickness 0.15)) (justify left bottom) hide)
    )
    (property "Author" "Antmicro" (at 205.74 91.44 0)
      (effects (font (size 1.27 1.27) (thickness 0.15)) (justify left bottom) hide)
    )
    (property "License" "Apache-2.0" (at 205.74 93.98 0)
      (effects (font (size 1.27 1.27) (thickness 0.15)) (justify left bottom) hide)
    )
    (pin "1")
    (instances
      (project "kria-k26-devboard"
        (path ""
          (reference "#PWR0370") (unit 1)
        )
      )
    )
  )

  (symbol (lib_id "kria-k26-devboard:GND") (at 247.65 88.9 0) (unit 1)
    (in_bom yes) (on_board yes) (dnp no) (fields_autoplaced)
    (property "Reference" "#PWR0376" (at 247.65 95.25 0)
      (effects (font (size 1.27 1.27)) hide)
    )
    (property "Value" "GND" (at 247.65 93.98 0)
      (effects (font (size 1.27 1.27)))
    )
    (property "Footprint" "" (at 256.54 96.52 0)
      (effects (font (size 1.27 1.27) (thickness 0.15)) (justify left bottom) hide)
    )
    (property "Datasheet" "" (at 256.54 101.6 0)
      (effects (font (size 1.27 1.27) (thickness 0.15)) (justify left bottom) hide)
    )
    (property "Author" "Antmicro" (at 256.54 96.52 0)
      (effects (font (size 1.27 1.27) (thickness 0.15)) (justify left bottom) hide)
    )
    (property "License" "Apache-2.0" (at 256.54 99.06 0)
      (effects (font (size 1.27 1.27) (thickness 0.15)) (justify left bottom) hide)
    )
    (pin "1")
    (instances
      (project "kria-k26-devboard"
        (path ""
          (reference "#PWR0376") (unit 1)
        )
      )
    )
  )

  (symbol (lib_id "kria-k26-devboard:AP62301_TSOT") (at 198.12 113.03 0) (unit 1)
    (in_bom yes) (on_board yes) (dnp no) (fields_autoplaced)
    (property "Reference" "U51" (at 208.28 105.41 0)
      (effects (font (size 1.27 1.27)))
    )
    (property "Value" "AP62301_TSOT" (at 208.28 107.95 0)
      (effects (font (size 1.27 1.27)))
    )
    (property "Footprint" "kria-k26-devboard-footprints:TSOT23-6" (at 196.85 129.54 0)
      (effects (font (size 1.27 1.27) (thickness 0.15)) (justify left bottom) hide)
    )
    (property "Datasheet" "https://www.diodes.com/assets/Datasheets/AP62300_AP62301_AP62300T.pdf" (at 196.85 121.92 0)
      (effects (font (size 1.27 1.27) (thickness 0.15)) (justify left bottom) hide)
    )
    (property "MPN" "AP62301WU-7" (at 196.85 127 0)
      (effects (font (size 1.27 1.27) (thickness 0.15)) (justify left bottom) hide)
    )
    (property "Manufacturer" "Diodes Incorporated" (at 196.85 124.46 0)
      (effects (font (size 1.27 1.27) (thickness 0.15)) (justify left bottom) hide)
    )
    (property "Author" "Antmicro" (at 233.68 120.65 0)
      (effects (font (size 1.27 1.27) (thickness 0.15)) (justify left bottom) hide)
    )
    (property "License" "Apache-2.0" (at 233.68 123.19 0)
      (effects (font (size 1.27 1.27) (thickness 0.15)) (justify left bottom) hide)
    )
    (pin "1")
    (pin "2")
    (pin "3")
    (pin "4")
    (pin "5")
    (pin "6")
    (instances
      (project "kria-k26-devboard"
        (path ""
          (reference "U51") (unit 1)
        )
      )
    )
  )

  (symbol (lib_id "kria-k26-devboard:C_100n_0402") (at 219.71 118.11 0) (unit 1)
    (in_bom yes) (on_board yes) (dnp no)
    (property "Reference" "C208" (at 226.06 116.84 0)
      (effects (font (size 1.524 1.524)))
    )
    (property "Value" "C_100n_0402" (at 219.71 121.92 0)
      (effects (font (size 1.524 1.524)) hide)
    )
    (property "Footprint" "kria-k26-devboard-footprints:C_0402_1005Metric" (at 224.79 113.03 0)
      (effects (font (size 1.27 1.27) (thickness 0.15)) (justify left bottom) hide)
    )
    (property "Datasheet" "https://search.murata.co.jp/Ceramy/image/img/A01X/G101/ENG/GRM155R61H104KE14-01.pdf" (at 219.71 118.11 0)
      (effects (font (size 1.27 1.27) (thickness 0.15)) (justify left bottom) hide)
    )
    (property "Manufacturer" "Murata" (at 224.79 107.95 0)
      (effects (font (size 1.27 1.27) (thickness 0.15)) (justify left bottom) hide)
    )
    (property "MPN" "GRM155R61H104KE14D" (at 224.79 110.49 0)
      (effects (font (size 1.27 1.27) (thickness 0.15)) (justify left bottom) hide)
    )
    (property "Val" "100n" (at 226.06 119.38 0)
      (effects (font (size 1.27 1.27) (thickness 0.15)))
    )
    (property "License" "Apache-2.0" (at 240.03 140.97 0)
      (effects (font (size 1.27 1.27) (thickness 0.15)) (justify left bottom) hide)
    )
    (property "Author" "Antmicro" (at 240.03 143.51 0)
      (effects (font (size 1.27 1.27) (thickness 0.15)) (justify left bottom) hide)
    )
    (property "Voltage" "50V" (at 240.03 146.05 0)
      (effects (font (size 1.27 1.27)) (justify left bottom) hide)
    )
    (property "Dielectric" "X5R" (at 240.03 148.59 0)
      (effects (font (size 1.27 1.27)) (justify left bottom) hide)
    )
    (pin "1")
    (pin "2")
    (instances
      (project "kria-k26-devboard"
        (path ""
          (reference "C208") (unit 1)
        )
      )
    )
  )

  (symbol (lib_id "kria-k26-devboard:C_22u_0603") (at 257.81 125.095 270) (unit 1)
    (in_bom yes) (on_board yes) (dnp no)
    (property "Reference" "C217" (at 258.445 125.73 90)
      (effects (font (size 1.524 1.524)) (justify left))
    )
    (property "Value" "C_22u_0603" (at 254 125.095 0)
      (effects (font (size 1.524 1.524)) hide)
    )
    (property "Footprint" "kria-k26-devboard-footprints:C_0603_1608Metric" (at 262.89 130.175 0)
      (effects (font (size 1.27 1.27) (thickness 0.15)) (justify left bottom) hide)
    )
    (property "Datasheet" " " (at 257.81 125.095 0)
      (effects (font (size 1.27 1.27) (thickness 0.15)) (justify left bottom) hide)
    )
    (property "Manufacturer" "Murata" (at 267.97 130.175 0)
      (effects (font (size 1.27 1.27) (thickness 0.15)) (justify left bottom) hide)
    )
    (property "MPN" "GRM188R60J226MEA0D" (at 265.43 130.175 0)
      (effects (font (size 1.27 1.27) (thickness 0.15)) (justify left bottom) hide)
    )
    (property "Val" "22u" (at 258.445 129.54 90)
      (effects (font (size 1.27 1.27) (thickness 0.15)) (justify left))
    )
    (property "License" "Apache-2.0" (at 234.95 145.415 0)
      (effects (font (size 1.27 1.27) (thickness 0.15)) (justify left bottom) hide)
    )
    (property "Author" "Antmicro" (at 232.41 145.415 0)
      (effects (font (size 1.27 1.27) (thickness 0.15)) (justify left bottom) hide)
    )
    (property "Voltage" "" (at 229.87 145.415 0)
      (effects (font (size 1.27 1.27)) (justify left bottom) hide)
    )
    (property "Dielectric" "" (at 227.33 145.415 0)
      (effects (font (size 1.27 1.27)) (justify left bottom) hide)
    )
    (pin "1")
    (pin "2")
    (instances
      (project "kria-k26-devboard"
        (path ""
          (reference "C217") (unit 1)
        )
      )
    )
  )

  (symbol (lib_id "kria-k26-devboard:C_22u_0603") (at 247.65 125.095 270) (unit 1)
    (in_bom yes) (on_board yes) (dnp no)
    (property "Reference" "C213" (at 248.285 125.73 90)
      (effects (font (size 1.524 1.524)) (justify left))
    )
    (property "Value" "C_22u_0603" (at 243.84 125.095 0)
      (effects (font (size 1.524 1.524)) hide)
    )
    (property "Footprint" "kria-k26-devboard-footprints:C_0603_1608Metric" (at 252.73 130.175 0)
      (effects (font (size 1.27 1.27) (thickness 0.15)) (justify left bottom) hide)
    )
    (property "Datasheet" " " (at 247.65 125.095 0)
      (effects (font (size 1.27 1.27) (thickness 0.15)) (justify left bottom) hide)
    )
    (property "Manufacturer" "Murata" (at 257.81 130.175 0)
      (effects (font (size 1.27 1.27) (thickness 0.15)) (justify left bottom) hide)
    )
    (property "MPN" "GRM188R60J226MEA0D" (at 255.27 130.175 0)
      (effects (font (size 1.27 1.27) (thickness 0.15)) (justify left bottom) hide)
    )
    (property "Val" "22u" (at 248.285 129.54 90)
      (effects (font (size 1.27 1.27) (thickness 0.15)) (justify left))
    )
    (property "License" "Apache-2.0" (at 224.79 145.415 0)
      (effects (font (size 1.27 1.27) (thickness 0.15)) (justify left bottom) hide)
    )
    (property "Author" "Antmicro" (at 222.25 145.415 0)
      (effects (font (size 1.27 1.27) (thickness 0.15)) (justify left bottom) hide)
    )
    (property "Voltage" "" (at 219.71 145.415 0)
      (effects (font (size 1.27 1.27)) (justify left bottom) hide)
    )
    (property "Dielectric" "" (at 217.17 145.415 0)
      (effects (font (size 1.27 1.27)) (justify left bottom) hide)
    )
    (pin "1")
    (pin "2")
    (instances
      (project "kria-k26-devboard"
        (path ""
          (reference "C213") (unit 1)
        )
      )
    )
  )

  (symbol (lib_id "kria-k26-devboard:R_12k4_0402") (at 236.855 116.84 270) (unit 1)
    (in_bom yes) (on_board yes) (dnp no) (fields_autoplaced)
    (property "Reference" "R135" (at 239.395 118.11 90)
      (effects (font (size 1.524 1.524)) (justify left))
    )
    (property "Value" "R_12k4_0402" (at 233.045 116.84 0)
      (effects (font (size 1.524 1.524)) hide)
    )
    (property "Footprint" "kria-k26-devboard-footprints:R_0402_1005Metric" (at 241.935 121.92 0)
      (effects (font (size 1.27 1.27) (thickness 0.15)) (justify left bottom) hide)
    )
    (property "Datasheet" "https://www.bourns.com/docs/product-datasheets/cr.pdf" (at 236.855 116.84 0)
      (effects (font (size 1.27 1.27) (thickness 0.15)) (justify left bottom) hide)
    )
    (property "Manufacturer" "Bourns" (at 247.015 121.92 0)
      (effects (font (size 1.27 1.27) (thickness 0.15)) (justify left bottom) hide)
    )
    (property "MPN" "CR0402-FX-1242GLF" (at 244.475 121.92 0)
      (effects (font (size 1.27 1.27) (thickness 0.15)) (justify left bottom) hide)
    )
    (property "Val" "12k4" (at 239.395 121.2849 90)
      (effects (font (size 1.27 1.27) (thickness 0.15)) (justify left))
    )
    (property "License" "Apache-2.0" (at 211.455 137.16 0)
      (effects (font (size 1.27 1.27) (thickness 0.15)) (justify left bottom) hide)
    )
    (property "Author" "Antmicro" (at 208.915 137.16 0)
      (effects (font (size 1.27 1.27) (thickness 0.15)) (justify left bottom) hide)
    )
    (property "Tolerance" "1%" (at 226.695 137.16 0)
      (effects (font (size 1.27 1.27)) (justify left bottom) hide)
    )
    (pin "1")
    (pin "2")
    (instances
      (project "kria-k26-devboard"
        (path ""
          (reference "R135") (unit 1)
        )
      )
    )
  )

  (symbol (lib_id "kria-k26-devboard:C_10u_25V_0603") (at 184.15 40.64 270) (unit 1)
    (in_bom yes) (on_board yes) (dnp no) (fields_autoplaced)
    (property "Reference" "C201" (at 186.69 41.9163 90)
      (effects (font (size 1.524 1.524)) (justify left))
    )
    (property "Value" "C_10u_25V_0603" (at 180.34 40.64 0)
      (effects (font (size 1.524 1.524)) hide)
    )
    (property "Footprint" "kria-k26-devboard-footprints:C_0603_1608Metric" (at 189.23 45.72 0)
      (effects (font (size 1.27 1.27) (thickness 0.15)) (justify left bottom) hide)
    )
    (property "Datasheet" " " (at 184.15 40.64 0)
      (effects (font (size 1.27 1.27) (thickness 0.15)) (justify left bottom) hide)
    )
    (property "Manufacturer" "TDK" (at 194.31 45.72 0)
      (effects (font (size 1.27 1.27) (thickness 0.15)) (justify left bottom) hide)
    )
    (property "MPN" "C1608X5R1E106M080AC" (at 191.77 45.72 0)
      (effects (font (size 1.27 1.27) (thickness 0.15)) (justify left bottom) hide)
    )
    (property "Val" "10u/25V" (at 186.69 45.0912 90)
      (effects (font (size 1.27 1.27) (thickness 0.15)) (justify left))
    )
    (property "License" "Apache-2.0" (at 161.29 60.96 0)
      (effects (font (size 1.27 1.27) (thickness 0.15)) (justify left bottom) hide)
    )
    (property "Author" "Antmicro" (at 158.75 60.96 0)
      (effects (font (size 1.27 1.27) (thickness 0.15)) (justify left bottom) hide)
    )
    (property "Voltage" "" (at 156.21 60.96 0)
      (effects (font (size 1.27 1.27)) (justify left bottom) hide)
    )
    (property "Dielectric" "" (at 153.67 60.96 0)
      (effects (font (size 1.27 1.27)) (justify left bottom) hide)
    )
    (pin "1")
    (pin "2")
    (instances
      (project "kria-k26-devboard"
        (path ""
          (reference "C201") (unit 1)
        )
      )
    )
  )

  (symbol (lib_id "kria-k26-devboard:C_10u_25V_0603") (at 184.15 78.74 270) (unit 1)
    (in_bom yes) (on_board yes) (dnp no) (fields_autoplaced)
    (property "Reference" "C202" (at 186.69 80.0163 90)
      (effects (font (size 1.524 1.524)) (justify left))
    )
    (property "Value" "C_10u_25V_0603" (at 180.34 78.74 0)
      (effects (font (size 1.524 1.524)) hide)
    )
    (property "Footprint" "kria-k26-devboard-footprints:C_0603_1608Metric" (at 189.23 83.82 0)
      (effects (font (size 1.27 1.27) (thickness 0.15)) (justify left bottom) hide)
    )
    (property "Datasheet" " " (at 184.15 78.74 0)
      (effects (font (size 1.27 1.27) (thickness 0.15)) (justify left bottom) hide)
    )
    (property "Manufacturer" "TDK" (at 194.31 83.82 0)
      (effects (font (size 1.27 1.27) (thickness 0.15)) (justify left bottom) hide)
    )
    (property "MPN" "C1608X5R1E106M080AC" (at 191.77 83.82 0)
      (effects (font (size 1.27 1.27) (thickness 0.15)) (justify left bottom) hide)
    )
    (property "Val" "10u/25V" (at 186.69 83.1912 90)
      (effects (font (size 1.27 1.27) (thickness 0.15)) (justify left))
    )
    (property "License" "Apache-2.0" (at 161.29 99.06 0)
      (effects (font (size 1.27 1.27) (thickness 0.15)) (justify left bottom) hide)
    )
    (property "Author" "Antmicro" (at 158.75 99.06 0)
      (effects (font (size 1.27 1.27) (thickness 0.15)) (justify left bottom) hide)
    )
    (property "Voltage" "" (at 156.21 99.06 0)
      (effects (font (size 1.27 1.27)) (justify left bottom) hide)
    )
    (property "Dielectric" "" (at 153.67 99.06 0)
      (effects (font (size 1.27 1.27)) (justify left bottom) hide)
    )
    (pin "1")
    (pin "2")
    (instances
      (project "kria-k26-devboard"
        (path ""
          (reference "C202") (unit 1)
        )
      )
    )
  )

  (symbol (lib_id "kria-k26-devboard:C_10u_25V_0603") (at 184.15 119.38 270) (unit 1)
    (in_bom yes) (on_board yes) (dnp no) (fields_autoplaced)
    (property "Reference" "C203" (at 187.325 120.6563 90)
      (effects (font (size 1.524 1.524)) (justify left))
    )
    (property "Value" "C_10u_25V_0603" (at 180.34 119.38 0)
      (effects (font (size 1.524 1.524)) hide)
    )
    (property "Footprint" "kria-k26-devboard-footprints:C_0603_1608Metric" (at 189.23 124.46 0)
      (effects (font (size 1.27 1.27) (thickness 0.15)) (justify left bottom) hide)
    )
    (property "Datasheet" " " (at 184.15 119.38 0)
      (effects (font (size 1.27 1.27) (thickness 0.15)) (justify left bottom) hide)
    )
    (property "Manufacturer" "TDK" (at 194.31 124.46 0)
      (effects (font (size 1.27 1.27) (thickness 0.15)) (justify left bottom) hide)
    )
    (property "MPN" "C1608X5R1E106M080AC" (at 191.77 124.46 0)
      (effects (font (size 1.27 1.27) (thickness 0.15)) (justify left bottom) hide)
    )
    (property "Val" "10u/25V" (at 187.325 123.8312 90)
      (effects (font (size 1.27 1.27) (thickness 0.15)) (justify left))
    )
    (property "License" "Apache-2.0" (at 161.29 139.7 0)
      (effects (font (size 1.27 1.27) (thickness 0.15)) (justify left bottom) hide)
    )
    (property "Author" "Antmicro" (at 158.75 139.7 0)
      (effects (font (size 1.27 1.27) (thickness 0.15)) (justify left bottom) hide)
    )
    (property "Voltage" "" (at 156.21 139.7 0)
      (effects (font (size 1.27 1.27)) (justify left bottom) hide)
    )
    (property "Dielectric" "" (at 153.67 139.7 0)
      (effects (font (size 1.27 1.27)) (justify left bottom) hide)
    )
    (pin "1")
    (pin "2")
    (instances
      (project "kria-k26-devboard"
        (path ""
          (reference "C203") (unit 1)
        )
      )
    )
  )

  (symbol (lib_id "kria-k26-devboard:AP62301_TSOT") (at 198.12 152.4 0) (unit 1)
    (in_bom yes) (on_board yes) (dnp no) (fields_autoplaced)
    (property "Reference" "U52" (at 208.28 144.78 0)
      (effects (font (size 1.27 1.27)))
    )
    (property "Value" "AP62301_TSOT" (at 208.28 147.32 0)
      (effects (font (size 1.27 1.27)))
    )
    (property "Footprint" "kria-k26-devboard-footprints:TSOT23-6" (at 196.85 168.91 0)
      (effects (font (size 1.27 1.27) (thickness 0.15)) (justify left bottom) hide)
    )
    (property "Datasheet" "https://www.diodes.com/assets/Datasheets/AP62300_AP62301_AP62300T.pdf" (at 196.85 161.29 0)
      (effects (font (size 1.27 1.27) (thickness 0.15)) (justify left bottom) hide)
    )
    (property "MPN" "AP62301WU-7" (at 196.85 166.37 0)
      (effects (font (size 1.27 1.27) (thickness 0.15)) (justify left bottom) hide)
    )
    (property "Manufacturer" "Diodes Incorporated" (at 196.85 163.83 0)
      (effects (font (size 1.27 1.27) (thickness 0.15)) (justify left bottom) hide)
    )
    (property "Author" "Antmicro" (at 233.68 160.02 0)
      (effects (font (size 1.27 1.27) (thickness 0.15)) (justify left bottom) hide)
    )
    (property "License" "Apache-2.0" (at 233.68 162.56 0)
      (effects (font (size 1.27 1.27) (thickness 0.15)) (justify left bottom) hide)
    )
    (pin "1")
    (pin "2")
    (pin "3")
    (pin "4")
    (pin "5")
    (pin "6")
    (instances
      (project "kria-k26-devboard"
        (path ""
          (reference "U52") (unit 1)
        )
      )
    )
  )

  (symbol (lib_id "kria-k26-devboard:C_100n_0402") (at 219.71 157.48 0) (unit 1)
    (in_bom yes) (on_board yes) (dnp no)
    (property "Reference" "C209" (at 226.06 156.21 0)
      (effects (font (size 1.524 1.524)))
    )
    (property "Value" "C_100n_0402" (at 219.71 161.29 0)
      (effects (font (size 1.524 1.524)) hide)
    )
    (property "Footprint" "kria-k26-devboard-footprints:C_0402_1005Metric" (at 224.79 152.4 0)
      (effects (font (size 1.27 1.27) (thickness 0.15)) (justify left bottom) hide)
    )
    (property "Datasheet" "https://search.murata.co.jp/Ceramy/image/img/A01X/G101/ENG/GRM155R61H104KE14-01.pdf" (at 219.71 157.48 0)
      (effects (font (size 1.27 1.27) (thickness 0.15)) (justify left bottom) hide)
    )
    (property "Manufacturer" "Murata" (at 224.79 147.32 0)
      (effects (font (size 1.27 1.27) (thickness 0.15)) (justify left bottom) hide)
    )
    (property "MPN" "GRM155R61H104KE14D" (at 224.79 149.86 0)
      (effects (font (size 1.27 1.27) (thickness 0.15)) (justify left bottom) hide)
    )
    (property "Val" "100n" (at 226.06 158.75 0)
      (effects (font (size 1.27 1.27) (thickness 0.15)))
    )
    (property "License" "Apache-2.0" (at 240.03 180.34 0)
      (effects (font (size 1.27 1.27) (thickness 0.15)) (justify left bottom) hide)
    )
    (property "Author" "Antmicro" (at 240.03 182.88 0)
      (effects (font (size 1.27 1.27) (thickness 0.15)) (justify left bottom) hide)
    )
    (property "Voltage" "50V" (at 240.03 185.42 0)
      (effects (font (size 1.27 1.27)) (justify left bottom) hide)
    )
    (property "Dielectric" "X5R" (at 240.03 187.96 0)
      (effects (font (size 1.27 1.27)) (justify left bottom) hide)
    )
    (pin "1")
    (pin "2")
    (instances
      (project "kria-k26-devboard"
        (path ""
          (reference "C209") (unit 1)
        )
      )
    )
  )

  (symbol (lib_id "kria-k26-devboard:C_22u_0603") (at 258.445 165.1 270) (unit 1)
    (in_bom yes) (on_board yes) (dnp no) (fields_autoplaced)
    (property "Reference" "C218" (at 260.985 166.3763 90)
      (effects (font (size 1.524 1.524)) (justify left))
    )
    (property "Value" "C_22u_0603" (at 254.635 165.1 0)
      (effects (font (size 1.524 1.524)) hide)
    )
    (property "Footprint" "kria-k26-devboard-footprints:C_0603_1608Metric" (at 263.525 170.18 0)
      (effects (font (size 1.27 1.27) (thickness 0.15)) (justify left bottom) hide)
    )
    (property "Datasheet" " " (at 258.445 165.1 0)
      (effects (font (size 1.27 1.27) (thickness 0.15)) (justify left bottom) hide)
    )
    (property "Manufacturer" "Murata" (at 268.605 170.18 0)
      (effects (font (size 1.27 1.27) (thickness 0.15)) (justify left bottom) hide)
    )
    (property "MPN" "GRM188R60J226MEA0D" (at 266.065 170.18 0)
      (effects (font (size 1.27 1.27) (thickness 0.15)) (justify left bottom) hide)
    )
    (property "Val" "22u" (at 260.985 169.5512 90)
      (effects (font (size 1.27 1.27) (thickness 0.15)) (justify left))
    )
    (property "License" "Apache-2.0" (at 235.585 185.42 0)
      (effects (font (size 1.27 1.27) (thickness 0.15)) (justify left bottom) hide)
    )
    (property "Author" "Antmicro" (at 233.045 185.42 0)
      (effects (font (size 1.27 1.27) (thickness 0.15)) (justify left bottom) hide)
    )
    (property "Voltage" "" (at 230.505 185.42 0)
      (effects (font (size 1.27 1.27)) (justify left bottom) hide)
    )
    (property "Dielectric" "" (at 227.965 185.42 0)
      (effects (font (size 1.27 1.27)) (justify left bottom) hide)
    )
    (pin "1")
    (pin "2")
    (instances
      (project "kria-k26-devboard"
        (path ""
          (reference "C218") (unit 1)
        )
      )
    )
  )

  (symbol (lib_id "kria-k26-devboard:C_22u_0603") (at 247.65 165.1 270) (unit 1)
    (in_bom yes) (on_board yes) (dnp no) (fields_autoplaced)
    (property "Reference" "C214" (at 250.19 166.3763 90)
      (effects (font (size 1.524 1.524)) (justify left))
    )
    (property "Value" "C_22u_0603" (at 243.84 165.1 0)
      (effects (font (size 1.524 1.524)) hide)
    )
    (property "Footprint" "kria-k26-devboard-footprints:C_0603_1608Metric" (at 252.73 170.18 0)
      (effects (font (size 1.27 1.27) (thickness 0.15)) (justify left bottom) hide)
    )
    (property "Datasheet" " " (at 247.65 165.1 0)
      (effects (font (size 1.27 1.27) (thickness 0.15)) (justify left bottom) hide)
    )
    (property "Manufacturer" "Murata" (at 257.81 170.18 0)
      (effects (font (size 1.27 1.27) (thickness 0.15)) (justify left bottom) hide)
    )
    (property "MPN" "GRM188R60J226MEA0D" (at 255.27 170.18 0)
      (effects (font (size 1.27 1.27) (thickness 0.15)) (justify left bottom) hide)
    )
    (property "Val" "22u" (at 250.19 169.5512 90)
      (effects (font (size 1.27 1.27) (thickness 0.15)) (justify left))
    )
    (property "License" "Apache-2.0" (at 224.79 185.42 0)
      (effects (font (size 1.27 1.27) (thickness 0.15)) (justify left bottom) hide)
    )
    (property "Author" "Antmicro" (at 222.25 185.42 0)
      (effects (font (size 1.27 1.27) (thickness 0.15)) (justify left bottom) hide)
    )
    (property "Voltage" "" (at 219.71 185.42 0)
      (effects (font (size 1.27 1.27)) (justify left bottom) hide)
    )
    (property "Dielectric" "" (at 217.17 185.42 0)
      (effects (font (size 1.27 1.27)) (justify left bottom) hide)
    )
    (pin "1")
    (pin "2")
    (instances
      (project "kria-k26-devboard"
        (path ""
          (reference "C214") (unit 1)
        )
      )
    )
  )

  (symbol (lib_id "kria-k26-devboard:GND") (at 184.15 163.83 0) (unit 1)
    (in_bom yes) (on_board yes) (dnp no) (fields_autoplaced)
    (property "Reference" "#PWR0372" (at 184.15 170.18 0)
      (effects (font (size 1.27 1.27)) hide)
    )
    (property "Value" "GND" (at 184.15 168.91 0)
      (effects (font (size 1.27 1.27)))
    )
    (property "Footprint" "" (at 193.04 171.45 0)
      (effects (font (size 1.27 1.27) (thickness 0.15)) (justify left bottom) hide)
    )
    (property "Datasheet" "" (at 193.04 176.53 0)
      (effects (font (size 1.27 1.27) (thickness 0.15)) (justify left bottom) hide)
    )
    (property "Author" "Antmicro" (at 193.04 171.45 0)
      (effects (font (size 1.27 1.27) (thickness 0.15)) (justify left bottom) hide)
    )
    (property "License" "Apache-2.0" (at 193.04 173.99 0)
      (effects (font (size 1.27 1.27) (thickness 0.15)) (justify left bottom) hide)
    )
    (pin "1")
    (instances
      (project "kria-k26-devboard"
        (path ""
          (reference "#PWR0372") (unit 1)
        )
      )
    )
  )

  (symbol (lib_id "kria-k26-devboard:C_10u_25V_0603") (at 184.15 158.75 270) (unit 1)
    (in_bom yes) (on_board yes) (dnp no) (fields_autoplaced)
    (property "Reference" "C204" (at 186.69 160.0263 90)
      (effects (font (size 1.524 1.524)) (justify left))
    )
    (property "Value" "C_10u_25V_0603" (at 180.34 158.75 0)
      (effects (font (size 1.524 1.524)) hide)
    )
    (property "Footprint" "kria-k26-devboard-footprints:C_0603_1608Metric" (at 189.23 163.83 0)
      (effects (font (size 1.27 1.27) (thickness 0.15)) (justify left bottom) hide)
    )
    (property "Datasheet" " " (at 184.15 158.75 0)
      (effects (font (size 1.27 1.27) (thickness 0.15)) (justify left bottom) hide)
    )
    (property "Manufacturer" "TDK" (at 194.31 163.83 0)
      (effects (font (size 1.27 1.27) (thickness 0.15)) (justify left bottom) hide)
    )
    (property "MPN" "C1608X5R1E106M080AC" (at 191.77 163.83 0)
      (effects (font (size 1.27 1.27) (thickness 0.15)) (justify left bottom) hide)
    )
    (property "Val" "10u/25V" (at 186.69 163.2012 90)
      (effects (font (size 1.27 1.27) (thickness 0.15)) (justify left))
    )
    (property "License" "Apache-2.0" (at 161.29 179.07 0)
      (effects (font (size 1.27 1.27) (thickness 0.15)) (justify left bottom) hide)
    )
    (property "Author" "Antmicro" (at 158.75 179.07 0)
      (effects (font (size 1.27 1.27) (thickness 0.15)) (justify left bottom) hide)
    )
    (property "Voltage" "" (at 156.21 179.07 0)
      (effects (font (size 1.27 1.27)) (justify left bottom) hide)
    )
    (property "Dielectric" "" (at 153.67 179.07 0)
      (effects (font (size 1.27 1.27)) (justify left bottom) hide)
    )
    (pin "1")
    (pin "2")
    (instances
      (project "kria-k26-devboard"
        (path ""
          (reference "C204") (unit 1)
        )
      )
    )
  )

  (symbol (lib_id "kria-k26-devboard:R_10k_0402") (at 236.855 45.72 270) (unit 1)
    (in_bom yes) (on_board yes) (dnp no) (fields_autoplaced)
    (property "Reference" "R132" (at 239.395 46.99 90)
      (effects (font (size 1.524 1.524)) (justify left))
    )
    (property "Value" "R_10k_0402" (at 233.045 45.72 0)
      (effects (font (size 1.524 1.524)) hide)
    )
    (property "Footprint" "kria-k26-devboard-footprints:R_0402_1005Metric" (at 241.935 50.8 0)
      (effects (font (size 1.27 1.27) (thickness 0.15)) (justify left bottom) hide)
    )
    (property "Datasheet" "https://www.bourns.com/docs/product-datasheets/cr.pdf" (at 236.855 45.72 0)
      (effects (font (size 1.27 1.27) (thickness 0.15)) (justify left bottom) hide)
    )
    (property "Manufacturer" "Bourns" (at 247.015 50.8 0)
      (effects (font (size 1.27 1.27) (thickness 0.15)) (justify left bottom) hide)
    )
    (property "MPN" "CR0402-FX-1002GLF" (at 244.475 50.8 0)
      (effects (font (size 1.27 1.27) (thickness 0.15)) (justify left bottom) hide)
    )
    (property "Val" "10k" (at 239.395 50.1649 90)
      (effects (font (size 1.27 1.27) (thickness 0.15)) (justify left))
    )
    (property "License" "Apache-2.0" (at 211.455 66.04 0)
      (effects (font (size 1.27 1.27) (thickness 0.15)) (justify left bottom) hide)
    )
    (property "Author" "Antmicro" (at 208.915 66.04 0)
      (effects (font (size 1.27 1.27) (thickness 0.15)) (justify left bottom) hide)
    )
    (property "Tolerance" "1%" (at 226.695 66.04 0)
      (effects (font (size 1.27 1.27)) (justify left bottom) hide)
    )
    (pin "1")
    (pin "2")
    (instances
      (project "kria-k26-devboard"
        (path ""
          (reference "R132") (unit 1)
        )
      )
    )
  )

  (symbol (lib_id "kria-k26-devboard:R_10k_0402") (at 236.855 83.82 270) (unit 1)
    (in_bom yes) (on_board yes) (dnp no) (fields_autoplaced)
    (property "Reference" "R134" (at 239.395 85.09 90)
      (effects (font (size 1.524 1.524)) (justify left))
    )
    (property "Value" "R_10k_0402" (at 233.045 83.82 0)
      (effects (font (size 1.524 1.524)) hide)
    )
    (property "Footprint" "kria-k26-devboard-footprints:R_0402_1005Metric" (at 241.935 88.9 0)
      (effects (font (size 1.27 1.27) (thickness 0.15)) (justify left bottom) hide)
    )
    (property "Datasheet" "https://www.bourns.com/docs/product-datasheets/cr.pdf" (at 236.855 83.82 0)
      (effects (font (size 1.27 1.27) (thickness 0.15)) (justify left bottom) hide)
    )
    (property "Manufacturer" "Bourns" (at 247.015 88.9 0)
      (effects (font (size 1.27 1.27) (thickness 0.15)) (justify left bottom) hide)
    )
    (property "MPN" "CR0402-FX-1002GLF" (at 244.475 88.9 0)
      (effects (font (size 1.27 1.27) (thickness 0.15)) (justify left bottom) hide)
    )
    (property "Val" "10k" (at 239.395 88.2649 90)
      (effects (font (size 1.27 1.27) (thickness 0.15)) (justify left))
    )
    (property "License" "Apache-2.0" (at 211.455 104.14 0)
      (effects (font (size 1.27 1.27) (thickness 0.15)) (justify left bottom) hide)
    )
    (property "Author" "Antmicro" (at 208.915 104.14 0)
      (effects (font (size 1.27 1.27) (thickness 0.15)) (justify left bottom) hide)
    )
    (property "Tolerance" "1%" (at 226.695 104.14 0)
      (effects (font (size 1.27 1.27)) (justify left bottom) hide)
    )
    (pin "1")
    (pin "2")
    (instances
      (project "kria-k26-devboard"
        (path ""
          (reference "R134") (unit 1)
        )
      )
    )
  )

  (symbol (lib_id "kria-k26-devboard:R_10k_0402") (at 236.855 125.095 270) (unit 1)
    (in_bom yes) (on_board yes) (dnp no) (fields_autoplaced)
    (property "Reference" "R136" (at 239.395 126.365 90)
      (effects (font (size 1.524 1.524)) (justify left))
    )
    (property "Value" "R_10k_0402" (at 233.045 125.095 0)
      (effects (font (size 1.524 1.524)) hide)
    )
    (property "Footprint" "kria-k26-devboard-footprints:R_0402_1005Metric" (at 241.935 130.175 0)
      (effects (font (size 1.27 1.27) (thickness 0.15)) (justify left bottom) hide)
    )
    (property "Datasheet" "https://www.bourns.com/docs/product-datasheets/cr.pdf" (at 236.855 125.095 0)
      (effects (font (size 1.27 1.27) (thickness 0.15)) (justify left bottom) hide)
    )
    (property "Manufacturer" "Bourns" (at 247.015 130.175 0)
      (effects (font (size 1.27 1.27) (thickness 0.15)) (justify left bottom) hide)
    )
    (property "MPN" "CR0402-FX-1002GLF" (at 244.475 130.175 0)
      (effects (font (size 1.27 1.27) (thickness 0.15)) (justify left bottom) hide)
    )
    (property "Val" "10k" (at 239.395 129.5399 90)
      (effects (font (size 1.27 1.27) (thickness 0.15)) (justify left))
    )
    (property "License" "Apache-2.0" (at 211.455 145.415 0)
      (effects (font (size 1.27 1.27) (thickness 0.15)) (justify left bottom) hide)
    )
    (property "Author" "Antmicro" (at 208.915 145.415 0)
      (effects (font (size 1.27 1.27) (thickness 0.15)) (justify left bottom) hide)
    )
    (property "Tolerance" "1%" (at 226.695 145.415 0)
      (effects (font (size 1.27 1.27)) (justify left bottom) hide)
    )
    (pin "1")
    (pin "2")
    (instances
      (project "kria-k26-devboard"
        (path ""
          (reference "R136") (unit 1)
        )
      )
    )
  )

  (symbol (lib_id "kria-k26-devboard:R_10k_0402") (at 236.855 165.1 270) (unit 1)
    (in_bom yes) (on_board yes) (dnp no) (fields_autoplaced)
    (property "Reference" "R138" (at 239.395 166.37 90)
      (effects (font (size 1.524 1.524)) (justify left))
    )
    (property "Value" "R_10k_0402" (at 233.045 165.1 0)
      (effects (font (size 1.524 1.524)) hide)
    )
    (property "Footprint" "kria-k26-devboard-footprints:R_0402_1005Metric" (at 241.935 170.18 0)
      (effects (font (size 1.27 1.27) (thickness 0.15)) (justify left bottom) hide)
    )
    (property "Datasheet" "https://www.bourns.com/docs/product-datasheets/cr.pdf" (at 236.855 165.1 0)
      (effects (font (size 1.27 1.27) (thickness 0.15)) (justify left bottom) hide)
    )
    (property "Manufacturer" "Bourns" (at 247.015 170.18 0)
      (effects (font (size 1.27 1.27) (thickness 0.15)) (justify left bottom) hide)
    )
    (property "MPN" "CR0402-FX-1002GLF" (at 244.475 170.18 0)
      (effects (font (size 1.27 1.27) (thickness 0.15)) (justify left bottom) hide)
    )
    (property "Val" "10k" (at 239.395 169.5449 90)
      (effects (font (size 1.27 1.27) (thickness 0.15)) (justify left))
    )
    (property "License" "Apache-2.0" (at 211.455 185.42 0)
      (effects (font (size 1.27 1.27) (thickness 0.15)) (justify left bottom) hide)
    )
    (property "Author" "Antmicro" (at 208.915 185.42 0)
      (effects (font (size 1.27 1.27) (thickness 0.15)) (justify left bottom) hide)
    )
    (property "Tolerance" "1%" (at 226.695 185.42 0)
      (effects (font (size 1.27 1.27)) (justify left bottom) hide)
    )
    (pin "1")
    (pin "2")
    (instances
      (project "kria-k26-devboard"
        (path ""
          (reference "R138") (unit 1)
        )
      )
    )
  )

  (symbol (lib_id "kria-k26-devboard:R_4k99_0402") (at 236.855 154.94 270) (unit 1)
    (in_bom yes) (on_board yes) (dnp no) (fields_autoplaced)
    (property "Reference" "R137" (at 239.395 156.21 90)
      (effects (font (size 1.524 1.524)) (justify left))
    )
    (property "Value" "R_4k99_0402" (at 233.045 154.94 0)
      (effects (font (size 1.524 1.524)) hide)
    )
    (property "Footprint" "kria-k26-devboard-footprints:R_0402_1005Metric" (at 241.935 160.02 0)
      (effects (font (size 1.27 1.27) (thickness 0.15)) (justify left bottom) hide)
    )
    (property "Datasheet" "https://www.bourns.com/docs/product-datasheets/cr.pdf" (at 236.855 154.94 0)
      (effects (font (size 1.27 1.27) (thickness 0.15)) (justify left bottom) hide)
    )
    (property "Manufacturer" "Bourns" (at 247.015 160.02 0)
      (effects (font (size 1.27 1.27) (thickness 0.15)) (justify left bottom) hide)
    )
    (property "MPN" "CR0402-FX-4991GLF" (at 244.475 160.02 0)
      (effects (font (size 1.27 1.27) (thickness 0.15)) (justify left bottom) hide)
    )
    (property "Val" "4k99" (at 239.395 159.3849 90)
      (effects (font (size 1.27 1.27) (thickness 0.15)) (justify left))
    )
    (property "License" "Apache-2.0" (at 211.455 175.26 0)
      (effects (font (size 1.27 1.27) (thickness 0.15)) (justify left bottom) hide)
    )
    (property "Author" "Antmicro" (at 208.915 175.26 0)
      (effects (font (size 1.27 1.27) (thickness 0.15)) (justify left bottom) hide)
    )
    (property "Tolerance" "1%" (at 226.695 175.26 0)
      (effects (font (size 1.27 1.27)) (justify left bottom) hide)
    )
    (pin "1")
    (pin "2")
    (instances
      (project "kria-k26-devboard"
        (path ""
          (reference "R137") (unit 1)
        )
      )
    )
  )

  (symbol (lib_id "kria-k26-devboard:R_21k5_0402") (at 236.855 75.565 270) (unit 1)
    (in_bom yes) (on_board yes) (dnp no) (fields_autoplaced)
    (property "Reference" "R133" (at 239.395 76.835 90)
      (effects (font (size 1.524 1.524)) (justify left))
    )
    (property "Value" "R_21k5_0402" (at 233.045 75.565 0)
      (effects (font (size 1.524 1.524)) hide)
    )
    (property "Footprint" "kria-k26-devboard-footprints:R_0402_1005Metric" (at 241.935 80.645 0)
      (effects (font (size 1.27 1.27) (thickness 0.15)) (justify left bottom) hide)
    )
    (property "Datasheet" "https://www.bourns.com/docs/product-datasheets/cr.pdf" (at 236.855 75.565 0)
      (effects (font (size 1.27 1.27) (thickness 0.15)) (justify left bottom) hide)
    )
    (property "Manufacturer" "Bourns" (at 247.015 80.645 0)
      (effects (font (size 1.27 1.27) (thickness 0.15)) (justify left bottom) hide)
    )
    (property "MPN" "CR0402-FX-2152GLF" (at 244.475 80.645 0)
      (effects (font (size 1.27 1.27) (thickness 0.15)) (justify left bottom) hide)
    )
    (property "Val" "21k5" (at 239.395 80.0099 90)
      (effects (font (size 1.27 1.27) (thickness 0.15)) (justify left))
    )
    (property "License" "Apache-2.0" (at 211.455 95.885 0)
      (effects (font (size 1.27 1.27) (thickness 0.15)) (justify left bottom) hide)
    )
    (property "Author" "Antmicro" (at 208.915 95.885 0)
      (effects (font (size 1.27 1.27) (thickness 0.15)) (justify left bottom) hide)
    )
    (property "Tolerance" "1%" (at 226.695 95.885 0)
      (effects (font (size 1.27 1.27)) (justify left bottom) hide)
    )
    (pin "1")
    (pin "2")
    (instances
      (project "kria-k26-devboard"
        (path ""
          (reference "R133") (unit 1)
        )
      )
    )
  )

  (symbol (lib_id "kria-k26-devboard:AP62301_TSOT") (at 321.31 66.04 0) (unit 1)
    (in_bom yes) (on_board yes) (dnp no) (fields_autoplaced)
    (property "Reference" "U55" (at 331.47 58.42 0)
      (effects (font (size 1.27 1.27)))
    )
    (property "Value" "AP62301_TSOT" (at 331.47 60.96 0)
      (effects (font (size 1.27 1.27)))
    )
    (property "Footprint" "kria-k26-devboard-footprints:TSOT23-6" (at 320.04 82.55 0)
      (effects (font (size 1.27 1.27) (thickness 0.15)) (justify left bottom) hide)
    )
    (property "Datasheet" "https://www.diodes.com/assets/Datasheets/AP62300_AP62301_AP62300T.pdf" (at 320.04 74.93 0)
      (effects (font (size 1.27 1.27) (thickness 0.15)) (justify left bottom) hide)
    )
    (property "MPN" "AP62301WU-7" (at 320.04 80.01 0)
      (effects (font (size 1.27 1.27) (thickness 0.15)) (justify left bottom) hide)
    )
    (property "Manufacturer" "Diodes Incorporated" (at 320.04 77.47 0)
      (effects (font (size 1.27 1.27) (thickness 0.15)) (justify left bottom) hide)
    )
    (property "Author" "Antmicro" (at 356.87 73.66 0)
      (effects (font (size 1.27 1.27) (thickness 0.15)) (justify left bottom) hide)
    )
    (property "License" "Apache-2.0" (at 356.87 76.2 0)
      (effects (font (size 1.27 1.27) (thickness 0.15)) (justify left bottom) hide)
    )
    (pin "1")
    (pin "2")
    (pin "3")
    (pin "4")
    (pin "5")
    (pin "6")
    (instances
      (project "kria-k26-devboard"
        (path ""
          (reference "U55") (unit 1)
        )
      )
    )
  )

  (symbol (lib_id "kria-k26-devboard:C_100n_0402") (at 342.9 71.12 0) (unit 1)
    (in_bom yes) (on_board yes) (dnp no)
    (property "Reference" "C222" (at 349.25 69.85 0)
      (effects (font (size 1.524 1.524)))
    )
    (property "Value" "C_100n_0402" (at 342.9 74.93 0)
      (effects (font (size 1.524 1.524)) hide)
    )
    (property "Footprint" "kria-k26-devboard-footprints:C_0402_1005Metric" (at 347.98 66.04 0)
      (effects (font (size 1.27 1.27) (thickness 0.15)) (justify left bottom) hide)
    )
    (property "Datasheet" "https://search.murata.co.jp/Ceramy/image/img/A01X/G101/ENG/GRM155R61H104KE14-01.pdf" (at 342.9 71.12 0)
      (effects (font (size 1.27 1.27) (thickness 0.15)) (justify left bottom) hide)
    )
    (property "Manufacturer" "Murata" (at 347.98 60.96 0)
      (effects (font (size 1.27 1.27) (thickness 0.15)) (justify left bottom) hide)
    )
    (property "MPN" "GRM155R61H104KE14D" (at 347.98 63.5 0)
      (effects (font (size 1.27 1.27) (thickness 0.15)) (justify left bottom) hide)
    )
    (property "Val" "100n" (at 349.25 72.39 0)
      (effects (font (size 1.27 1.27) (thickness 0.15)))
    )
    (property "License" "Apache-2.0" (at 363.22 93.98 0)
      (effects (font (size 1.27 1.27) (thickness 0.15)) (justify left bottom) hide)
    )
    (property "Author" "Antmicro" (at 363.22 96.52 0)
      (effects (font (size 1.27 1.27) (thickness 0.15)) (justify left bottom) hide)
    )
    (property "Voltage" "50V" (at 363.22 99.06 0)
      (effects (font (size 1.27 1.27)) (justify left bottom) hide)
    )
    (property "Dielectric" "X5R" (at 363.22 101.6 0)
      (effects (font (size 1.27 1.27)) (justify left bottom) hide)
    )
    (pin "1")
    (pin "2")
    (instances
      (project "kria-k26-devboard"
        (path ""
          (reference "C222") (unit 1)
        )
      )
    )
  )

  (symbol (lib_id "kria-k26-devboard:C_22u_0603") (at 382.27 79.375 270) (unit 1)
    (in_bom yes) (on_board yes) (dnp no)
    (property "Reference" "C226" (at 382.905 80.01 90)
      (effects (font (size 1.524 1.524)) (justify left))
    )
    (property "Value" "C_22u_0603" (at 378.46 79.375 0)
      (effects (font (size 1.524 1.524)) hide)
    )
    (property "Footprint" "kria-k26-devboard-footprints:C_0603_1608Metric" (at 387.35 84.455 0)
      (effects (font (size 1.27 1.27) (thickness 0.15)) (justify left bottom) hide)
    )
    (property "Datasheet" " " (at 382.27 79.375 0)
      (effects (font (size 1.27 1.27) (thickness 0.15)) (justify left bottom) hide)
    )
    (property "Manufacturer" "Murata" (at 392.43 84.455 0)
      (effects (font (size 1.27 1.27) (thickness 0.15)) (justify left bottom) hide)
    )
    (property "MPN" "GRM188R60J226MEA0D" (at 389.89 84.455 0)
      (effects (font (size 1.27 1.27) (thickness 0.15)) (justify left bottom) hide)
    )
    (property "Val" "22u" (at 382.905 83.82 90)
      (effects (font (size 1.27 1.27) (thickness 0.15)) (justify left))
    )
    (property "License" "Apache-2.0" (at 359.41 99.695 0)
      (effects (font (size 1.27 1.27) (thickness 0.15)) (justify left bottom) hide)
    )
    (property "Author" "Antmicro" (at 356.87 99.695 0)
      (effects (font (size 1.27 1.27) (thickness 0.15)) (justify left bottom) hide)
    )
    (property "Voltage" "" (at 354.33 99.695 0)
      (effects (font (size 1.27 1.27)) (justify left bottom) hide)
    )
    (property "Dielectric" "" (at 351.79 99.695 0)
      (effects (font (size 1.27 1.27)) (justify left bottom) hide)
    )
    (pin "1")
    (pin "2")
    (instances
      (project "kria-k26-devboard"
        (path ""
          (reference "C226") (unit 1)
        )
      )
    )
  )

  (symbol (lib_id "kria-k26-devboard:C_22u_0603") (at 370.84 79.375 270) (unit 1)
    (in_bom yes) (on_board yes) (dnp no)
    (property "Reference" "C224" (at 371.475 80.01 90)
      (effects (font (size 1.524 1.524)) (justify left))
    )
    (property "Value" "C_22u_0603" (at 367.03 79.375 0)
      (effects (font (size 1.524 1.524)) hide)
    )
    (property "Footprint" "kria-k26-devboard-footprints:C_0603_1608Metric" (at 375.92 84.455 0)
      (effects (font (size 1.27 1.27) (thickness 0.15)) (justify left bottom) hide)
    )
    (property "Datasheet" " " (at 370.84 79.375 0)
      (effects (font (size 1.27 1.27) (thickness 0.15)) (justify left bottom) hide)
    )
    (property "Manufacturer" "Murata" (at 381 84.455 0)
      (effects (font (size 1.27 1.27) (thickness 0.15)) (justify left bottom) hide)
    )
    (property "MPN" "GRM188R60J226MEA0D" (at 378.46 84.455 0)
      (effects (font (size 1.27 1.27) (thickness 0.15)) (justify left bottom) hide)
    )
    (property "Val" "22u" (at 371.475 83.82 90)
      (effects (font (size 1.27 1.27) (thickness 0.15)) (justify left))
    )
    (property "License" "Apache-2.0" (at 347.98 99.695 0)
      (effects (font (size 1.27 1.27) (thickness 0.15)) (justify left bottom) hide)
    )
    (property "Author" "Antmicro" (at 345.44 99.695 0)
      (effects (font (size 1.27 1.27) (thickness 0.15)) (justify left bottom) hide)
    )
    (property "Voltage" "" (at 342.9 99.695 0)
      (effects (font (size 1.27 1.27)) (justify left bottom) hide)
    )
    (property "Dielectric" "" (at 340.36 99.695 0)
      (effects (font (size 1.27 1.27)) (justify left bottom) hide)
    )
    (pin "1")
    (pin "2")
    (instances
      (project "kria-k26-devboard"
        (path ""
          (reference "C224") (unit 1)
        )
      )
    )
  )

  (symbol (lib_id "kria-k26-devboard:GND") (at 307.34 77.47 0) (unit 1)
    (in_bom yes) (on_board yes) (dnp no) (fields_autoplaced)
    (property "Reference" "#PWR0383" (at 307.34 83.82 0)
      (effects (font (size 1.27 1.27)) hide)
    )
    (property "Value" "GND" (at 307.34 82.55 0)
      (effects (font (size 1.27 1.27)))
    )
    (property "Footprint" "" (at 316.23 85.09 0)
      (effects (font (size 1.27 1.27) (thickness 0.15)) (justify left bottom) hide)
    )
    (property "Datasheet" "" (at 316.23 90.17 0)
      (effects (font (size 1.27 1.27) (thickness 0.15)) (justify left bottom) hide)
    )
    (property "Author" "Antmicro" (at 316.23 85.09 0)
      (effects (font (size 1.27 1.27) (thickness 0.15)) (justify left bottom) hide)
    )
    (property "License" "Apache-2.0" (at 316.23 87.63 0)
      (effects (font (size 1.27 1.27) (thickness 0.15)) (justify left bottom) hide)
    )
    (pin "1")
    (instances
      (project "kria-k26-devboard"
        (path ""
          (reference "#PWR0383") (unit 1)
        )
      )
    )
  )

  (symbol (lib_id "kria-k26-devboard:GND") (at 382.27 84.455 0) (unit 1)
    (in_bom yes) (on_board yes) (dnp no) (fields_autoplaced)
    (property "Reference" "#PWR0387" (at 382.27 90.805 0)
      (effects (font (size 1.27 1.27)) hide)
    )
    (property "Value" "GND" (at 382.27 89.535 0)
      (effects (font (size 1.27 1.27)))
    )
    (property "Footprint" "" (at 391.16 92.075 0)
      (effects (font (size 1.27 1.27) (thickness 0.15)) (justify left bottom) hide)
    )
    (property "Datasheet" "" (at 391.16 97.155 0)
      (effects (font (size 1.27 1.27) (thickness 0.15)) (justify left bottom) hide)
    )
    (property "Author" "Antmicro" (at 391.16 92.075 0)
      (effects (font (size 1.27 1.27) (thickness 0.15)) (justify left bottom) hide)
    )
    (property "License" "Apache-2.0" (at 391.16 94.615 0)
      (effects (font (size 1.27 1.27) (thickness 0.15)) (justify left bottom) hide)
    )
    (pin "1")
    (instances
      (project "kria-k26-devboard"
        (path ""
          (reference "#PWR0387") (unit 1)
        )
      )
    )
  )

  (symbol (lib_id "kria-k26-devboard:C_10u_25V_0603") (at 307.34 72.39 270) (unit 1)
    (in_bom yes) (on_board yes) (dnp no) (fields_autoplaced)
    (property "Reference" "C220" (at 309.88 73.6663 90)
      (effects (font (size 1.524 1.524)) (justify left))
    )
    (property "Value" "C_10u_25V_0603" (at 303.53 72.39 0)
      (effects (font (size 1.524 1.524)) hide)
    )
    (property "Footprint" "kria-k26-devboard-footprints:C_0603_1608Metric" (at 312.42 77.47 0)
      (effects (font (size 1.27 1.27) (thickness 0.15)) (justify left bottom) hide)
    )
    (property "Datasheet" " " (at 307.34 72.39 0)
      (effects (font (size 1.27 1.27) (thickness 0.15)) (justify left bottom) hide)
    )
    (property "Manufacturer" "TDK" (at 317.5 77.47 0)
      (effects (font (size 1.27 1.27) (thickness 0.15)) (justify left bottom) hide)
    )
    (property "MPN" "C1608X5R1E106M080AC" (at 314.96 77.47 0)
      (effects (font (size 1.27 1.27) (thickness 0.15)) (justify left bottom) hide)
    )
    (property "Val" "10u/25V" (at 309.88 76.8412 90)
      (effects (font (size 1.27 1.27) (thickness 0.15)) (justify left))
    )
    (property "License" "Apache-2.0" (at 284.48 92.71 0)
      (effects (font (size 1.27 1.27) (thickness 0.15)) (justify left bottom) hide)
    )
    (property "Author" "Antmicro" (at 281.94 92.71 0)
      (effects (font (size 1.27 1.27) (thickness 0.15)) (justify left bottom) hide)
    )
    (property "Voltage" "" (at 279.4 92.71 0)
      (effects (font (size 1.27 1.27)) (justify left bottom) hide)
    )
    (property "Dielectric" "" (at 276.86 92.71 0)
      (effects (font (size 1.27 1.27)) (justify left bottom) hide)
    )
    (pin "1")
    (pin "2")
    (instances
      (project "kria-k26-devboard"
        (path ""
          (reference "C220") (unit 1)
        )
      )
    )
  )

  (symbol (lib_id "kria-k26-devboard:R_10k_0402") (at 360.68 80.01 270) (unit 1)
    (in_bom yes) (on_board yes) (dnp no) (fields_autoplaced)
    (property "Reference" "R147" (at 363.22 81.28 90)
      (effects (font (size 1.524 1.524)) (justify left))
    )
    (property "Value" "R_10k_0402" (at 356.87 80.01 0)
      (effects (font (size 1.524 1.524)) hide)
    )
    (property "Footprint" "kria-k26-devboard-footprints:R_0402_1005Metric" (at 365.76 85.09 0)
      (effects (font (size 1.27 1.27) (thickness 0.15)) (justify left bottom) hide)
    )
    (property "Datasheet" "https://www.bourns.com/docs/product-datasheets/cr.pdf" (at 360.68 80.01 0)
      (effects (font (size 1.27 1.27) (thickness 0.15)) (justify left bottom) hide)
    )
    (property "Manufacturer" "Bourns" (at 370.84 85.09 0)
      (effects (font (size 1.27 1.27) (thickness 0.15)) (justify left bottom) hide)
    )
    (property "MPN" "CR0402-FX-1002GLF" (at 368.3 85.09 0)
      (effects (font (size 1.27 1.27) (thickness 0.15)) (justify left bottom) hide)
    )
    (property "Val" "10k" (at 363.22 84.4549 90)
      (effects (font (size 1.27 1.27) (thickness 0.15)) (justify left))
    )
    (property "License" "Apache-2.0" (at 335.28 100.33 0)
      (effects (font (size 1.27 1.27) (thickness 0.15)) (justify left bottom) hide)
    )
    (property "Author" "Antmicro" (at 332.74 100.33 0)
      (effects (font (size 1.27 1.27) (thickness 0.15)) (justify left bottom) hide)
    )
    (property "Tolerance" "1%" (at 350.52 100.33 0)
      (effects (font (size 1.27 1.27)) (justify left bottom) hide)
    )
    (pin "1")
    (pin "2")
    (instances
      (project "kria-k26-devboard"
        (path ""
          (reference "R147") (unit 1)
        )
      )
    )
  )

  (symbol (lib_id "kria-k26-devboard:R_4k99_0402") (at 360.68 69.85 270) (unit 1)
    (in_bom yes) (on_board yes) (dnp no) (fields_autoplaced)
    (property "Reference" "R146" (at 363.22 71.12 90)
      (effects (font (size 1.524 1.524)) (justify left))
    )
    (property "Value" "R_4k99_0402" (at 356.87 69.85 0)
      (effects (font (size 1.524 1.524)) hide)
    )
    (property "Footprint" "kria-k26-devboard-footprints:R_0402_1005Metric" (at 365.76 74.93 0)
      (effects (font (size 1.27 1.27) (thickness 0.15)) (justify left bottom) hide)
    )
    (property "Datasheet" "https://www.bourns.com/docs/product-datasheets/cr.pdf" (at 360.68 69.85 0)
      (effects (font (size 1.27 1.27) (thickness 0.15)) (justify left bottom) hide)
    )
    (property "Manufacturer" "Bourns" (at 370.84 74.93 0)
      (effects (font (size 1.27 1.27) (thickness 0.15)) (justify left bottom) hide)
    )
    (property "MPN" "CR0402-FX-4991GLF" (at 368.3 74.93 0)
      (effects (font (size 1.27 1.27) (thickness 0.15)) (justify left bottom) hide)
    )
    (property "Val" "4k99" (at 363.22 74.2949 90)
      (effects (font (size 1.27 1.27) (thickness 0.15)) (justify left))
    )
    (property "License" "Apache-2.0" (at 335.28 90.17 0)
      (effects (font (size 1.27 1.27) (thickness 0.15)) (justify left bottom) hide)
    )
    (property "Author" "Antmicro" (at 332.74 90.17 0)
      (effects (font (size 1.27 1.27) (thickness 0.15)) (justify left bottom) hide)
    )
    (property "Tolerance" "1%" (at 350.52 90.17 0)
      (effects (font (size 1.27 1.27)) (justify left bottom) hide)
    )
    (pin "1")
    (pin "2")
    (instances
      (project "kria-k26-devboard"
        (path ""
          (reference "R146") (unit 1)
        )
      )
    )
  )

  (symbol (lib_id "kria-k26-devboard:AP62301_TSOT") (at 321.31 34.29 0) (unit 1)
    (in_bom yes) (on_board yes) (dnp no) (fields_autoplaced)
    (property "Reference" "U54" (at 331.47 26.67 0)
      (effects (font (size 1.27 1.27)))
    )
    (property "Value" "AP62301_TSOT" (at 331.47 29.21 0)
      (effects (font (size 1.27 1.27)))
    )
    (property "Footprint" "kria-k26-devboard-footprints:TSOT23-6" (at 320.04 50.8 0)
      (effects (font (size 1.27 1.27) (thickness 0.15)) (justify left bottom) hide)
    )
    (property "Datasheet" "https://www.diodes.com/assets/Datasheets/AP62300_AP62301_AP62300T.pdf" (at 320.04 43.18 0)
      (effects (font (size 1.27 1.27) (thickness 0.15)) (justify left bottom) hide)
    )
    (property "MPN" "AP62301WU-7" (at 320.04 48.26 0)
      (effects (font (size 1.27 1.27) (thickness 0.15)) (justify left bottom) hide)
    )
    (property "Manufacturer" "Diodes Incorporated" (at 320.04 45.72 0)
      (effects (font (size 1.27 1.27) (thickness 0.15)) (justify left bottom) hide)
    )
    (property "Author" "Antmicro" (at 356.87 41.91 0)
      (effects (font (size 1.27 1.27) (thickness 0.15)) (justify left bottom) hide)
    )
    (property "License" "Apache-2.0" (at 356.87 44.45 0)
      (effects (font (size 1.27 1.27) (thickness 0.15)) (justify left bottom) hide)
    )
    (pin "1")
    (pin "2")
    (pin "3")
    (pin "4")
    (pin "5")
    (pin "6")
    (instances
      (project "kria-k26-devboard"
        (path ""
          (reference "U54") (unit 1)
        )
      )
    )
  )

  (symbol (lib_id "kria-k26-devboard:C_100n_0402") (at 342.265 39.37 0) (unit 1)
    (in_bom yes) (on_board yes) (dnp no)
    (property "Reference" "C221" (at 349.25 38.1 0)
      (effects (font (size 1.524 1.524)))
    )
    (property "Value" "C_100n_0402" (at 342.265 43.18 0)
      (effects (font (size 1.524 1.524)) hide)
    )
    (property "Footprint" "kria-k26-devboard-footprints:C_0402_1005Metric" (at 347.345 34.29 0)
      (effects (font (size 1.27 1.27) (thickness 0.15)) (justify left bottom) hide)
    )
    (property "Datasheet" "https://search.murata.co.jp/Ceramy/image/img/A01X/G101/ENG/GRM155R61H104KE14-01.pdf" (at 342.265 39.37 0)
      (effects (font (size 1.27 1.27) (thickness 0.15)) (justify left bottom) hide)
    )
    (property "Manufacturer" "Murata" (at 347.345 29.21 0)
      (effects (font (size 1.27 1.27) (thickness 0.15)) (justify left bottom) hide)
    )
    (property "MPN" "GRM155R61H104KE14D" (at 347.345 31.75 0)
      (effects (font (size 1.27 1.27) (thickness 0.15)) (justify left bottom) hide)
    )
    (property "Val" "100n" (at 348.615 40.64 0)
      (effects (font (size 1.27 1.27) (thickness 0.15)))
    )
    (property "License" "Apache-2.0" (at 362.585 62.23 0)
      (effects (font (size 1.27 1.27) (thickness 0.15)) (justify left bottom) hide)
    )
    (property "Author" "Antmicro" (at 362.585 64.77 0)
      (effects (font (size 1.27 1.27) (thickness 0.15)) (justify left bottom) hide)
    )
    (property "Voltage" "50V" (at 362.585 67.31 0)
      (effects (font (size 1.27 1.27)) (justify left bottom) hide)
    )
    (property "Dielectric" "X5R" (at 362.585 69.85 0)
      (effects (font (size 1.27 1.27)) (justify left bottom) hide)
    )
    (pin "1")
    (pin "2")
    (instances
      (project "kria-k26-devboard"
        (path ""
          (reference "C221") (unit 1)
        )
      )
    )
  )

  (symbol (lib_id "kria-k26-devboard:C_22u_0603") (at 382.905 50.8 90) (unit 1)
    (in_bom yes) (on_board yes) (dnp no)
    (property "Reference" "C225" (at 383.54 46.355 90)
      (effects (font (size 1.524 1.524)) (justify right))
    )
    (property "Value" "C_22u_0603" (at 386.715 50.8 0)
      (effects (font (size 1.524 1.524)) hide)
    )
    (property "Footprint" "kria-k26-devboard-footprints:C_0603_1608Metric" (at 377.825 45.72 0)
      (effects (font (size 1.27 1.27) (thickness 0.15)) (justify left bottom) hide)
    )
    (property "Datasheet" " " (at 382.905 50.8 0)
      (effects (font (size 1.27 1.27) (thickness 0.15)) (justify left bottom) hide)
    )
    (property "Manufacturer" "Murata" (at 372.745 45.72 0)
      (effects (font (size 1.27 1.27) (thickness 0.15)) (justify left bottom) hide)
    )
    (property "MPN" "GRM188R60J226MEA0D" (at 375.285 45.72 0)
      (effects (font (size 1.27 1.27) (thickness 0.15)) (justify left bottom) hide)
    )
    (property "Val" "22u" (at 383.54 50.165 90)
      (effects (font (size 1.27 1.27) (thickness 0.15)) (justify right))
    )
    (property "License" "Apache-2.0" (at 405.765 30.48 0)
      (effects (font (size 1.27 1.27) (thickness 0.15)) (justify left bottom) hide)
    )
    (property "Author" "Antmicro" (at 408.305 30.48 0)
      (effects (font (size 1.27 1.27) (thickness 0.15)) (justify left bottom) hide)
    )
    (property "Voltage" "" (at 410.845 30.48 0)
      (effects (font (size 1.27 1.27)) (justify left bottom) hide)
    )
    (property "Dielectric" "" (at 413.385 30.48 0)
      (effects (font (size 1.27 1.27)) (justify left bottom) hide)
    )
    (pin "1")
    (pin "2")
    (instances
      (project "kria-k26-devboard"
        (path ""
          (reference "C225") (unit 1)
        )
      )
    )
  )

  (symbol (lib_id "kria-k26-devboard:C_22u_0603") (at 370.84 50.8 90) (unit 1)
    (in_bom yes) (on_board yes) (dnp no)
    (property "Reference" "C223" (at 371.475 46.355 90)
      (effects (font (size 1.524 1.524)) (justify right))
    )
    (property "Value" "C_22u_0603" (at 374.65 50.8 0)
      (effects (font (size 1.524 1.524)) hide)
    )
    (property "Footprint" "kria-k26-devboard-footprints:C_0603_1608Metric" (at 365.76 45.72 0)
      (effects (font (size 1.27 1.27) (thickness 0.15)) (justify left bottom) hide)
    )
    (property "Datasheet" " " (at 370.84 50.8 0)
      (effects (font (size 1.27 1.27) (thickness 0.15)) (justify left bottom) hide)
    )
    (property "Manufacturer" "Murata" (at 360.68 45.72 0)
      (effects (font (size 1.27 1.27) (thickness 0.15)) (justify left bottom) hide)
    )
    (property "MPN" "GRM188R60J226MEA0D" (at 363.22 45.72 0)
      (effects (font (size 1.27 1.27) (thickness 0.15)) (justify left bottom) hide)
    )
    (property "Val" "22u" (at 371.475 50.165 90)
      (effects (font (size 1.27 1.27) (thickness 0.15)) (justify right))
    )
    (property "License" "Apache-2.0" (at 393.7 30.48 0)
      (effects (font (size 1.27 1.27) (thickness 0.15)) (justify left bottom) hide)
    )
    (property "Author" "Antmicro" (at 396.24 30.48 0)
      (effects (font (size 1.27 1.27) (thickness 0.15)) (justify left bottom) hide)
    )
    (property "Voltage" "" (at 398.78 30.48 0)
      (effects (font (size 1.27 1.27)) (justify left bottom) hide)
    )
    (property "Dielectric" "" (at 401.32 30.48 0)
      (effects (font (size 1.27 1.27)) (justify left bottom) hide)
    )
    (pin "1")
    (pin "2")
    (instances
      (project "kria-k26-devboard"
        (path ""
          (reference "C223") (unit 1)
        )
      )
    )
  )

  (symbol (lib_id "kria-k26-devboard:R_31k6_0402") (at 360.045 38.1 270) (unit 1)
    (in_bom yes) (on_board yes) (dnp no) (fields_autoplaced)
    (property "Reference" "R144" (at 362.585 39.37 90)
      (effects (font (size 1.524 1.524)) (justify left))
    )
    (property "Value" "R_31k6_0402" (at 356.235 38.1 0)
      (effects (font (size 1.524 1.524)) hide)
    )
    (property "Footprint" "kria-k26-devboard-footprints:R_0402_1005Metric" (at 365.125 43.18 0)
      (effects (font (size 1.27 1.27) (thickness 0.15)) (justify left bottom) hide)
    )
    (property "Datasheet" "https://www.bourns.com/docs/product-datasheets/cr.pdf" (at 360.045 38.1 0)
      (effects (font (size 1.27 1.27) (thickness 0.15)) (justify left bottom) hide)
    )
    (property "Manufacturer" "Bourns" (at 370.205 43.18 0)
      (effects (font (size 1.27 1.27) (thickness 0.15)) (justify left bottom) hide)
    )
    (property "MPN" "CR0402-FX-3162GLF" (at 367.665 43.18 0)
      (effects (font (size 1.27 1.27) (thickness 0.15)) (justify left bottom) hide)
    )
    (property "Val" "31k6" (at 362.585 42.5449 90)
      (effects (font (size 1.27 1.27) (thickness 0.15)) (justify left))
    )
    (property "License" "Apache-2.0" (at 334.645 58.42 0)
      (effects (font (size 1.27 1.27) (thickness 0.15)) (justify left bottom) hide)
    )
    (property "Author" "Antmicro" (at 332.105 58.42 0)
      (effects (font (size 1.27 1.27) (thickness 0.15)) (justify left bottom) hide)
    )
    (property "Tolerance" "1%" (at 349.885 58.42 0)
      (effects (font (size 1.27 1.27)) (justify left bottom) hide)
    )
    (pin "1")
    (pin "2")
    (instances
      (project "kria-k26-devboard"
        (path ""
          (reference "R144") (unit 1)
        )
      )
    )
  )

  (symbol (lib_id "kria-k26-devboard:GND") (at 307.34 46.355 0) (unit 1)
    (in_bom yes) (on_board yes) (dnp no) (fields_autoplaced)
    (property "Reference" "#PWR0382" (at 307.34 52.705 0)
      (effects (font (size 1.27 1.27)) hide)
    )
    (property "Value" "GND" (at 307.34 51.435 0)
      (effects (font (size 1.27 1.27)))
    )
    (property "Footprint" "" (at 316.23 53.975 0)
      (effects (font (size 1.27 1.27) (thickness 0.15)) (justify left bottom) hide)
    )
    (property "Datasheet" "" (at 316.23 59.055 0)
      (effects (font (size 1.27 1.27) (thickness 0.15)) (justify left bottom) hide)
    )
    (property "Author" "Antmicro" (at 316.23 53.975 0)
      (effects (font (size 1.27 1.27) (thickness 0.15)) (justify left bottom) hide)
    )
    (property "License" "Apache-2.0" (at 316.23 56.515 0)
      (effects (font (size 1.27 1.27) (thickness 0.15)) (justify left bottom) hide)
    )
    (pin "1")
    (instances
      (project "kria-k26-devboard"
        (path ""
          (reference "#PWR0382") (unit 1)
        )
      )
    )
  )

  (symbol (lib_id "kria-k26-devboard:GND") (at 382.905 50.8 0) (unit 1)
    (in_bom yes) (on_board yes) (dnp no) (fields_autoplaced)
    (property "Reference" "#PWR0386" (at 382.905 57.15 0)
      (effects (font (size 1.27 1.27)) hide)
    )
    (property "Value" "GND" (at 382.905 55.88 0)
      (effects (font (size 1.27 1.27)))
    )
    (property "Footprint" "" (at 391.795 58.42 0)
      (effects (font (size 1.27 1.27) (thickness 0.15)) (justify left bottom) hide)
    )
    (property "Datasheet" "" (at 391.795 63.5 0)
      (effects (font (size 1.27 1.27) (thickness 0.15)) (justify left bottom) hide)
    )
    (property "Author" "Antmicro" (at 391.795 58.42 0)
      (effects (font (size 1.27 1.27) (thickness 0.15)) (justify left bottom) hide)
    )
    (property "License" "Apache-2.0" (at 391.795 60.96 0)
      (effects (font (size 1.27 1.27) (thickness 0.15)) (justify left bottom) hide)
    )
    (pin "1")
    (instances
      (project "kria-k26-devboard"
        (path ""
          (reference "#PWR0386") (unit 1)
        )
      )
    )
  )

  (symbol (lib_id "kria-k26-devboard:C_10u_25V_0603") (at 307.34 41.275 270) (unit 1)
    (in_bom yes) (on_board yes) (dnp no) (fields_autoplaced)
    (property "Reference" "C219" (at 309.88 42.5513 90)
      (effects (font (size 1.524 1.524)) (justify left))
    )
    (property "Value" "C_10u_25V_0603" (at 303.53 41.275 0)
      (effects (font (size 1.524 1.524)) hide)
    )
    (property "Footprint" "kria-k26-devboard-footprints:C_0603_1608Metric" (at 312.42 46.355 0)
      (effects (font (size 1.27 1.27) (thickness 0.15)) (justify left bottom) hide)
    )
    (property "Datasheet" " " (at 307.34 41.275 0)
      (effects (font (size 1.27 1.27) (thickness 0.15)) (justify left bottom) hide)
    )
    (property "Manufacturer" "TDK" (at 317.5 46.355 0)
      (effects (font (size 1.27 1.27) (thickness 0.15)) (justify left bottom) hide)
    )
    (property "MPN" "C1608X5R1E106M080AC" (at 314.96 46.355 0)
      (effects (font (size 1.27 1.27) (thickness 0.15)) (justify left bottom) hide)
    )
    (property "Val" "10u/25V" (at 309.88 45.7262 90)
      (effects (font (size 1.27 1.27) (thickness 0.15)) (justify left))
    )
    (property "License" "Apache-2.0" (at 284.48 61.595 0)
      (effects (font (size 1.27 1.27) (thickness 0.15)) (justify left bottom) hide)
    )
    (property "Author" "Antmicro" (at 281.94 61.595 0)
      (effects (font (size 1.27 1.27) (thickness 0.15)) (justify left bottom) hide)
    )
    (property "Voltage" "" (at 279.4 61.595 0)
      (effects (font (size 1.27 1.27)) (justify left bottom) hide)
    )
    (property "Dielectric" "" (at 276.86 61.595 0)
      (effects (font (size 1.27 1.27)) (justify left bottom) hide)
    )
    (pin "1")
    (pin "2")
    (instances
      (project "kria-k26-devboard"
        (path ""
          (reference "C219") (unit 1)
        )
      )
    )
  )

  (symbol (lib_id "kria-k26-devboard:R_10k_0402") (at 360.045 45.72 270) (unit 1)
    (in_bom yes) (on_board yes) (dnp no) (fields_autoplaced)
    (property "Reference" "R145" (at 362.585 46.99 90)
      (effects (font (size 1.524 1.524)) (justify left))
    )
    (property "Value" "R_10k_0402" (at 356.235 45.72 0)
      (effects (font (size 1.524 1.524)) hide)
    )
    (property "Footprint" "kria-k26-devboard-footprints:R_0402_1005Metric" (at 365.125 50.8 0)
      (effects (font (size 1.27 1.27) (thickness 0.15)) (justify left bottom) hide)
    )
    (property "Datasheet" "https://www.bourns.com/docs/product-datasheets/cr.pdf" (at 360.045 45.72 0)
      (effects (font (size 1.27 1.27) (thickness 0.15)) (justify left bottom) hide)
    )
    (property "Manufacturer" "Bourns" (at 370.205 50.8 0)
      (effects (font (size 1.27 1.27) (thickness 0.15)) (justify left bottom) hide)
    )
    (property "MPN" "CR0402-FX-1002GLF" (at 367.665 50.8 0)
      (effects (font (size 1.27 1.27) (thickness 0.15)) (justify left bottom) hide)
    )
    (property "Val" "10k" (at 362.585 50.1649 90)
      (effects (font (size 1.27 1.27) (thickness 0.15)) (justify left))
    )
    (property "License" "Apache-2.0" (at 334.645 66.04 0)
      (effects (font (size 1.27 1.27) (thickness 0.15)) (justify left bottom) hide)
    )
    (property "Author" "Antmicro" (at 332.105 66.04 0)
      (effects (font (size 1.27 1.27) (thickness 0.15)) (justify left bottom) hide)
    )
    (property "Tolerance" "1%" (at 349.885 66.04 0)
      (effects (font (size 1.27 1.27)) (justify left bottom) hide)
    )
    (pin "1")
    (pin "2")
    (instances
      (project "kria-k26-devboard"
        (path ""
          (reference "R145") (unit 1)
        )
      )
    )
  )

  (symbol (lib_id "kria-k26-devboard:AP62301_TSOT") (at 198.12 193.04 0) (unit 1)
    (in_bom yes) (on_board yes) (dnp no) (fields_autoplaced)
    (property "Reference" "U53" (at 208.28 185.42 0)
      (effects (font (size 1.27 1.27)))
    )
    (property "Value" "AP62301_TSOT" (at 208.28 187.96 0)
      (effects (font (size 1.27 1.27)))
    )
    (property "Footprint" "kria-k26-devboard-footprints:TSOT23-6" (at 196.85 209.55 0)
      (effects (font (size 1.27 1.27) (thickness 0.15)) (justify left bottom) hide)
    )
    (property "Datasheet" "https://www.diodes.com/assets/Datasheets/AP62300_AP62301_AP62300T.pdf" (at 196.85 201.93 0)
      (effects (font (size 1.27 1.27) (thickness 0.15)) (justify left bottom) hide)
    )
    (property "MPN" "AP62301WU-7" (at 196.85 207.01 0)
      (effects (font (size 1.27 1.27) (thickness 0.15)) (justify left bottom) hide)
    )
    (property "Manufacturer" "Diodes Incorporated" (at 196.85 204.47 0)
      (effects (font (size 1.27 1.27) (thickness 0.15)) (justify left bottom) hide)
    )
    (property "Author" "Antmicro" (at 233.68 200.66 0)
      (effects (font (size 1.27 1.27) (thickness 0.15)) (justify left bottom) hide)
    )
    (property "License" "Apache-2.0" (at 233.68 203.2 0)
      (effects (font (size 1.27 1.27) (thickness 0.15)) (justify left bottom) hide)
    )
    (pin "1")
    (pin "2")
    (pin "3")
    (pin "4")
    (pin "5")
    (pin "6")
    (instances
      (project "kria-k26-devboard"
        (path ""
          (reference "U53") (unit 1)
        )
      )
    )
  )

  (symbol (lib_id "kria-k26-devboard:C_100n_0402") (at 219.71 198.12 0) (unit 1)
    (in_bom yes) (on_board yes) (dnp no)
    (property "Reference" "C210" (at 226.06 196.85 0)
      (effects (font (size 1.524 1.524)))
    )
    (property "Value" "C_100n_0402" (at 219.71 201.93 0)
      (effects (font (size 1.524 1.524)) hide)
    )
    (property "Footprint" "kria-k26-devboard-footprints:C_0402_1005Metric" (at 224.79 193.04 0)
      (effects (font (size 1.27 1.27) (thickness 0.15)) (justify left bottom) hide)
    )
    (property "Datasheet" "https://search.murata.co.jp/Ceramy/image/img/A01X/G101/ENG/GRM155R61H104KE14-01.pdf" (at 219.71 198.12 0)
      (effects (font (size 1.27 1.27) (thickness 0.15)) (justify left bottom) hide)
    )
    (property "Manufacturer" "Murata" (at 224.79 187.96 0)
      (effects (font (size 1.27 1.27) (thickness 0.15)) (justify left bottom) hide)
    )
    (property "MPN" "GRM155R61H104KE14D" (at 224.79 190.5 0)
      (effects (font (size 1.27 1.27) (thickness 0.15)) (justify left bottom) hide)
    )
    (property "Val" "100n" (at 226.06 199.39 0)
      (effects (font (size 1.27 1.27) (thickness 0.15)))
    )
    (property "License" "Apache-2.0" (at 240.03 220.98 0)
      (effects (font (size 1.27 1.27) (thickness 0.15)) (justify left bottom) hide)
    )
    (property "Author" "Antmicro" (at 240.03 223.52 0)
      (effects (font (size 1.27 1.27) (thickness 0.15)) (justify left bottom) hide)
    )
    (property "Voltage" "50V" (at 240.03 226.06 0)
      (effects (font (size 1.27 1.27)) (justify left bottom) hide)
    )
    (property "Dielectric" "X5R" (at 240.03 228.6 0)
      (effects (font (size 1.27 1.27)) (justify left bottom) hide)
    )
    (pin "1")
    (pin "2")
    (instances
      (project "kria-k26-devboard"
        (path ""
          (reference "C210") (unit 1)
        )
      )
    )
  )

  (symbol (lib_id "kria-k26-devboard:C_22u_0603") (at 250.19 205.74 270) (unit 1)
    (in_bom yes) (on_board yes) (dnp no) (fields_autoplaced)
    (property "Reference" "C215" (at 252.73 207.0163 90)
      (effects (font (size 1.524 1.524)) (justify left))
    )
    (property "Value" "C_22u_0603" (at 246.38 205.74 0)
      (effects (font (size 1.524 1.524)) hide)
    )
    (property "Footprint" "kria-k26-devboard-footprints:C_0603_1608Metric" (at 255.27 210.82 0)
      (effects (font (size 1.27 1.27) (thickness 0.15)) (justify left bottom) hide)
    )
    (property "Datasheet" " " (at 250.19 205.74 0)
      (effects (font (size 1.27 1.27) (thickness 0.15)) (justify left bottom) hide)
    )
    (property "Manufacturer" "Murata" (at 260.35 210.82 0)
      (effects (font (size 1.27 1.27) (thickness 0.15)) (justify left bottom) hide)
    )
    (property "MPN" "GRM188R60J226MEA0D" (at 257.81 210.82 0)
      (effects (font (size 1.27 1.27) (thickness 0.15)) (justify left bottom) hide)
    )
    (property "Val" "22u" (at 252.73 210.1912 90)
      (effects (font (size 1.27 1.27) (thickness 0.15)) (justify left))
    )
    (property "License" "Apache-2.0" (at 227.33 226.06 0)
      (effects (font (size 1.27 1.27) (thickness 0.15)) (justify left bottom) hide)
    )
    (property "Author" "Antmicro" (at 224.79 226.06 0)
      (effects (font (size 1.27 1.27) (thickness 0.15)) (justify left bottom) hide)
    )
    (property "Voltage" "" (at 222.25 226.06 0)
      (effects (font (size 1.27 1.27)) (justify left bottom) hide)
    )
    (property "Dielectric" "" (at 219.71 226.06 0)
      (effects (font (size 1.27 1.27)) (justify left bottom) hide)
    )
    (pin "1")
    (pin "2")
    (instances
      (project "kria-k26-devboard"
        (path ""
          (reference "C215") (unit 1)
        )
      )
    )
  )

  (symbol (lib_id "kria-k26-devboard:GND") (at 184.15 204.47 0) (unit 1)
    (in_bom yes) (on_board yes) (dnp no) (fields_autoplaced)
    (property "Reference" "#PWR0373" (at 184.15 210.82 0)
      (effects (font (size 1.27 1.27)) hide)
    )
    (property "Value" "GND" (at 184.15 209.55 0)
      (effects (font (size 1.27 1.27)))
    )
    (property "Footprint" "" (at 193.04 212.09 0)
      (effects (font (size 1.27 1.27) (thickness 0.15)) (justify left bottom) hide)
    )
    (property "Datasheet" "" (at 193.04 217.17 0)
      (effects (font (size 1.27 1.27) (thickness 0.15)) (justify left bottom) hide)
    )
    (property "Author" "Antmicro" (at 193.04 212.09 0)
      (effects (font (size 1.27 1.27) (thickness 0.15)) (justify left bottom) hide)
    )
    (property "License" "Apache-2.0" (at 193.04 214.63 0)
      (effects (font (size 1.27 1.27) (thickness 0.15)) (justify left bottom) hide)
    )
    (pin "1")
    (instances
      (project "kria-k26-devboard"
        (path ""
          (reference "#PWR0373") (unit 1)
        )
      )
    )
  )

  (symbol (lib_id "kria-k26-devboard:GND") (at 250.19 210.82 0) (unit 1)
    (in_bom yes) (on_board yes) (dnp no) (fields_autoplaced)
    (property "Reference" "#PWR0377" (at 250.19 217.17 0)
      (effects (font (size 1.27 1.27)) hide)
    )
    (property "Value" "GND" (at 250.19 215.9 0)
      (effects (font (size 1.27 1.27)))
    )
    (property "Footprint" "" (at 259.08 218.44 0)
      (effects (font (size 1.27 1.27) (thickness 0.15)) (justify left bottom) hide)
    )
    (property "Datasheet" "" (at 259.08 223.52 0)
      (effects (font (size 1.27 1.27) (thickness 0.15)) (justify left bottom) hide)
    )
    (property "Author" "Antmicro" (at 259.08 218.44 0)
      (effects (font (size 1.27 1.27) (thickness 0.15)) (justify left bottom) hide)
    )
    (property "License" "Apache-2.0" (at 259.08 220.98 0)
      (effects (font (size 1.27 1.27) (thickness 0.15)) (justify left bottom) hide)
    )
    (pin "1")
    (instances
      (project "kria-k26-devboard"
        (path ""
          (reference "#PWR0377") (unit 1)
        )
      )
    )
  )

  (symbol (lib_id "kria-k26-devboard:C_10u_25V_0603") (at 184.15 199.39 270) (unit 1)
    (in_bom yes) (on_board yes) (dnp no) (fields_autoplaced)
    (property "Reference" "C205" (at 186.69 200.6663 90)
      (effects (font (size 1.524 1.524)) (justify left))
    )
    (property "Value" "C_10u_25V_0603" (at 180.34 199.39 0)
      (effects (font (size 1.524 1.524)) hide)
    )
    (property "Footprint" "kria-k26-devboard-footprints:C_0603_1608Metric" (at 189.23 204.47 0)
      (effects (font (size 1.27 1.27) (thickness 0.15)) (justify left bottom) hide)
    )
    (property "Datasheet" " " (at 184.15 199.39 0)
      (effects (font (size 1.27 1.27) (thickness 0.15)) (justify left bottom) hide)
    )
    (property "Manufacturer" "TDK" (at 194.31 204.47 0)
      (effects (font (size 1.27 1.27) (thickness 0.15)) (justify left bottom) hide)
    )
    (property "MPN" "C1608X5R1E106M080AC" (at 191.77 204.47 0)
      (effects (font (size 1.27 1.27) (thickness 0.15)) (justify left bottom) hide)
    )
    (property "Val" "10u/25V" (at 186.69 203.8412 90)
      (effects (font (size 1.27 1.27) (thickness 0.15)) (justify left))
    )
    (property "License" "Apache-2.0" (at 161.29 219.71 0)
      (effects (font (size 1.27 1.27) (thickness 0.15)) (justify left bottom) hide)
    )
    (property "Author" "Antmicro" (at 158.75 219.71 0)
      (effects (font (size 1.27 1.27) (thickness 0.15)) (justify left bottom) hide)
    )
    (property "Voltage" "" (at 156.21 219.71 0)
      (effects (font (size 1.27 1.27)) (justify left bottom) hide)
    )
    (property "Dielectric" "" (at 153.67 219.71 0)
      (effects (font (size 1.27 1.27)) (justify left bottom) hide)
    )
    (pin "1")
    (pin "2")
    (instances
      (project "kria-k26-devboard"
        (path ""
          (reference "C205") (unit 1)
        )
      )
    )
  )

  (symbol (lib_id "kria-k26-devboard:R_10k_0402") (at 238.125 205.74 270) (unit 1)
    (in_bom yes) (on_board yes) (dnp no) (fields_autoplaced)
    (property "Reference" "R140" (at 240.665 207.01 90)
      (effects (font (size 1.524 1.524)) (justify left))
    )
    (property "Value" "R_10k_0402" (at 234.315 205.74 0)
      (effects (font (size 1.524 1.524)) hide)
    )
    (property "Footprint" "kria-k26-devboard-footprints:R_0402_1005Metric" (at 243.205 210.82 0)
      (effects (font (size 1.27 1.27) (thickness 0.15)) (justify left bottom) hide)
    )
    (property "Datasheet" "https://www.bourns.com/docs/product-datasheets/cr.pdf" (at 238.125 205.74 0)
      (effects (font (size 1.27 1.27) (thickness 0.15)) (justify left bottom) hide)
    )
    (property "Manufacturer" "Bourns" (at 248.285 210.82 0)
      (effects (font (size 1.27 1.27) (thickness 0.15)) (justify left bottom) hide)
    )
    (property "MPN" "CR0402-FX-1002GLF" (at 245.745 210.82 0)
      (effects (font (size 1.27 1.27) (thickness 0.15)) (justify left bottom) hide)
    )
    (property "Val" "10k" (at 240.665 210.1849 90)
      (effects (font (size 1.27 1.27) (thickness 0.15)) (justify left))
    )
    (property "License" "Apache-2.0" (at 212.725 226.06 0)
      (effects (font (size 1.27 1.27) (thickness 0.15)) (justify left bottom) hide)
    )
    (property "Author" "Antmicro" (at 210.185 226.06 0)
      (effects (font (size 1.27 1.27) (thickness 0.15)) (justify left bottom) hide)
    )
    (property "Tolerance" "1%" (at 227.965 226.06 0)
      (effects (font (size 1.27 1.27)) (justify left bottom) hide)
    )
    (pin "1")
    (pin "2")
    (instances
      (project "kria-k26-devboard"
        (path ""
          (reference "R140") (unit 1)
        )
      )
    )
  )

  (symbol (lib_id "kria-k26-devboard:R_2k49_0402") (at 238.125 195.58 270) (unit 1)
    (in_bom yes) (on_board yes) (dnp no) (fields_autoplaced)
    (property "Reference" "R139" (at 240.665 196.85 90)
      (effects (font (size 1.524 1.524)) (justify left))
    )
    (property "Value" "R_2k49_0402" (at 234.315 195.58 0)
      (effects (font (size 1.524 1.524)) hide)
    )
    (property "Footprint" "kria-k26-devboard-footprints:R_0402_1005Metric" (at 243.205 200.66 0)
      (effects (font (size 1.27 1.27) (thickness 0.15)) (justify left bottom) hide)
    )
    (property "Datasheet" "https://www.bourns.com/docs/product-datasheets/cr.pdf" (at 238.125 195.58 0)
      (effects (font (size 1.27 1.27) (thickness 0.15)) (justify left bottom) hide)
    )
    (property "Manufacturer" "Bourns" (at 248.285 200.66 0)
      (effects (font (size 1.27 1.27) (thickness 0.15)) (justify left bottom) hide)
    )
    (property "MPN" "CR0402-FX-2491GLF" (at 245.745 200.66 0)
      (effects (font (size 1.27 1.27) (thickness 0.15)) (justify left bottom) hide)
    )
    (property "Val" "2k49" (at 240.665 200.0249 90)
      (effects (font (size 1.27 1.27) (thickness 0.15)) (justify left))
    )
    (property "License" "Apache-2.0" (at 212.725 215.9 0)
      (effects (font (size 1.27 1.27) (thickness 0.15)) (justify left bottom) hide)
    )
    (property "Author" "Antmicro" (at 210.185 215.9 0)
      (effects (font (size 1.27 1.27) (thickness 0.15)) (justify left bottom) hide)
    )
    (property "Tolerance" "1%" (at 227.965 215.9 0)
      (effects (font (size 1.27 1.27)) (justify left bottom) hide)
    )
    (pin "1")
    (pin "2")
    (instances
      (project "kria-k26-devboard"
        (path ""
          (reference "R139") (unit 1)
        )
      )
    )
  )

  (symbol (lib_id "kria-k26-devboard:L_1u_2.6A_0806") (at 230.505 113.03 0) (unit 1)
    (in_bom yes) (on_board yes) (dnp no)
    (property "Reference" "L5" (at 233.045 107.95 0)
      (effects (font (size 1.524 1.524)))
    )
    (property "Value" "L_1u_2.6A_0806" (at 233.045 106.68 0)
      (effects (font (size 1.524 1.524)) hide)
    )
    (property "Footprint" "kria-k26-devboard-footprints:L_0806_2016Metric" (at 251.46 104.14 0)
      (effects (font (size 1.27 1.27) (thickness 0.15)) (justify left bottom) hide)
    )
    (property "Datasheet" "https://www.bourns.com/docs/Product-Datasheets/SRP2010.pdf" (at 231.902 112.268 0)
      (effects (font (size 1.27 1.27) (thickness 0.15)) (justify left bottom) hide)
    )
    (property "Manufacturer" "Bourns" (at 234.315 93.98 0)
      (effects (font (size 1.27 1.27) (thickness 0.15)) (justify left bottom) hide)
    )
    (property "MPN" "SRP2010-1R0M" (at 238.125 96.52 0)
      (effects (font (size 1.27 1.27) (thickness 0.15)) (justify left bottom) hide)
    )
    (property "Size" "2.0x1.6" (at 233.68 101.6 0)
      (effects (font (size 1.27 1.27) (thickness 0.15)) (justify left bottom) hide)
    )
    (property "Val" "1u/2.6A" (at 233.045 110.49 0)
      (effects (font (size 1.27 1.27) (thickness 0.15)))
    )
    (property "ISat" "" (at 244.475 129.54 0)
      (effects (font (size 1.27 1.27)) (justify left) hide)
    )
    (property "IMax" "" (at 244.475 133.35 0)
      (effects (font (size 1.27 1.27) (thickness 0.15)) (justify left bottom) hide)
    )
    (property "Author" "Antmicro" (at 244.475 138.43 0)
      (effects (font (size 1.27 1.27) (thickness 0.15)) (justify left bottom) hide)
    )
    (property "License" "Apache-2.0" (at 244.475 140.97 0)
      (effects (font (size 1.27 1.27) (thickness 0.15)) (justify left bottom) hide)
    )
    (pin "1")
    (pin "2")
    (instances
      (project "kria-k26-devboard"
        (path ""
          (reference "L5") (unit 1)
        )
      )
    )
  )

  (symbol (lib_id "kria-k26-devboard:L_1u_2.6A_0806") (at 353.695 34.29 0) (unit 1)
    (in_bom yes) (on_board yes) (dnp no)
    (property "Reference" "L8" (at 356.235 29.21 0)
      (effects (font (size 1.524 1.524)))
    )
    (property "Value" "L_1u_2.6A_0806" (at 356.235 27.94 0)
      (effects (font (size 1.524 1.524)) hide)
    )
    (property "Footprint" "kria-k26-devboard-footprints:L_0806_2016Metric" (at 374.65 25.4 0)
      (effects (font (size 1.27 1.27) (thickness 0.15)) (justify left bottom) hide)
    )
    (property "Datasheet" "https://www.bourns.com/docs/Product-Datasheets/SRP2010.pdf" (at 355.092 33.528 0)
      (effects (font (size 1.27 1.27) (thickness 0.15)) (justify left bottom) hide)
    )
    (property "Manufacturer" "Bourns" (at 357.505 15.24 0)
      (effects (font (size 1.27 1.27) (thickness 0.15)) (justify left bottom) hide)
    )
    (property "MPN" "SRP2010-1R0M" (at 361.315 17.78 0)
      (effects (font (size 1.27 1.27) (thickness 0.15)) (justify left bottom) hide)
    )
    (property "Size" "2.0x1.6" (at 356.87 22.86 0)
      (effects (font (size 1.27 1.27) (thickness 0.15)) (justify left bottom) hide)
    )
    (property "Val" "1u/2.6A" (at 356.235 31.75 0)
      (effects (font (size 1.27 1.27) (thickness 0.15)))
    )
    (property "ISat" "" (at 367.665 50.8 0)
      (effects (font (size 1.27 1.27)) (justify left) hide)
    )
    (property "IMax" "" (at 367.665 54.61 0)
      (effects (font (size 1.27 1.27) (thickness 0.15)) (justify left bottom) hide)
    )
    (property "Author" "Antmicro" (at 367.665 59.69 0)
      (effects (font (size 1.27 1.27) (thickness 0.15)) (justify left bottom) hide)
    )
    (property "License" "Apache-2.0" (at 367.665 62.23 0)
      (effects (font (size 1.27 1.27) (thickness 0.15)) (justify left bottom) hide)
    )
    (pin "1")
    (pin "2")
    (instances
      (project "kria-k26-devboard"
        (path ""
          (reference "L8") (unit 1)
        )
      )
    )
  )

  (symbol (lib_id "kria-k26-devboard:L_1u_2.6A_0806") (at 354.33 66.04 0) (unit 1)
    (in_bom yes) (on_board yes) (dnp no)
    (property "Reference" "L9" (at 356.87 60.96 0)
      (effects (font (size 1.524 1.524)))
    )
    (property "Value" "L_1u_2.6A_0806" (at 356.87 59.69 0)
      (effects (font (size 1.524 1.524)) hide)
    )
    (property "Footprint" "kria-k26-devboard-footprints:L_0806_2016Metric" (at 375.285 57.15 0)
      (effects (font (size 1.27 1.27) (thickness 0.15)) (justify left bottom) hide)
    )
    (property "Datasheet" "https://www.bourns.com/docs/Product-Datasheets/SRP2010.pdf" (at 355.727 65.278 0)
      (effects (font (size 1.27 1.27) (thickness 0.15)) (justify left bottom) hide)
    )
    (property "Manufacturer" "Bourns" (at 358.14 46.99 0)
      (effects (font (size 1.27 1.27) (thickness 0.15)) (justify left bottom) hide)
    )
    (property "MPN" "SRP2010-1R0M" (at 361.95 49.53 0)
      (effects (font (size 1.27 1.27) (thickness 0.15)) (justify left bottom) hide)
    )
    (property "Size" "2.0x1.6" (at 357.505 54.61 0)
      (effects (font (size 1.27 1.27) (thickness 0.15)) (justify left bottom) hide)
    )
    (property "Val" "1u/2.6A" (at 356.87 63.5 0)
      (effects (font (size 1.27 1.27) (thickness 0.15)))
    )
    (property "ISat" "" (at 368.3 82.55 0)
      (effects (font (size 1.27 1.27)) (justify left) hide)
    )
    (property "IMax" "" (at 368.3 86.36 0)
      (effects (font (size 1.27 1.27) (thickness 0.15)) (justify left bottom) hide)
    )
    (property "Author" "Antmicro" (at 368.3 91.44 0)
      (effects (font (size 1.27 1.27) (thickness 0.15)) (justify left bottom) hide)
    )
    (property "License" "Apache-2.0" (at 368.3 93.98 0)
      (effects (font (size 1.27 1.27) (thickness 0.15)) (justify left bottom) hide)
    )
    (pin "1")
    (pin "2")
    (instances
      (project "kria-k26-devboard"
        (path ""
          (reference "L9") (unit 1)
        )
      )
    )
  )

  (symbol (lib_id "kria-k26-devboard:R_1k_0402") (at 187.325 241.935 0) (unit 1)
    (in_bom yes) (on_board yes) (dnp no)
    (property "Reference" "R130" (at 189.865 236.855 0)
      (effects (font (size 1.524 1.524)))
    )
    (property "Value" "R_1k_0402" (at 187.325 245.745 0)
      (effects (font (size 1.27 1.27) (thickness 0.15)) (justify left bottom) hide)
    )
    (property "Footprint" "kria-k26-devboard-footprints:R_0402_1005Metric" (at 192.405 236.855 0)
      (effects (font (size 1.27 1.27) (thickness 0.15)) (justify left bottom) hide)
    )
    (property "Datasheet" "https://www.bourns.com/docs/product-datasheets/cr.pdf" (at 187.325 241.935 0)
      (effects (font (size 1.27 1.27) (thickness 0.15)) (justify left bottom) hide)
    )
    (property "Manufacturer" "Bourns" (at 192.405 231.775 0)
      (effects (font (size 1.27 1.27) (thickness 0.15)) (justify left bottom) hide)
    )
    (property "MPN" "CR0402-FX-1001GLF" (at 192.405 234.315 0)
      (effects (font (size 1.27 1.27) (thickness 0.15)) (justify left bottom) hide)
    )
    (property "Val" "1k" (at 189.865 239.395 0)
      (effects (font (size 1.27 1.27) (thickness 0.15)))
    )
    (property "License" "Apache-2.0" (at 207.645 267.335 0)
      (effects (font (size 1.27 1.27) (thickness 0.15)) (justify left bottom) hide)
    )
    (property "Author" "Antmicro" (at 207.645 269.875 0)
      (effects (font (size 1.27 1.27) (thickness 0.15)) (justify left bottom) hide)
    )
    (property "Tolerance" "1%" (at 207.645 252.095 0)
      (effects (font (size 1.27 1.27)) (justify left bottom) hide)
    )
    (pin "1")
    (pin "2")
    (instances
      (project "kria-k26-devboard"
        (path ""
          (reference "R130") (unit 1)
        )
      )
    )
  )

  (symbol (lib_id "kria-k26-devboard:GND") (at 195.58 264.795 0) (unit 1)
    (in_bom yes) (on_board yes) (dnp no) (fields_autoplaced)
    (property "Reference" "#PWR0375" (at 195.58 271.145 0)
      (effects (font (size 1.27 1.27)) hide)
    )
    (property "Value" "GND" (at 195.58 269.875 0)
      (effects (font (size 1.27 1.27)))
    )
    (property "Footprint" "" (at 204.47 272.415 0)
      (effects (font (size 1.27 1.27) (thickness 0.15)) (justify left bottom) hide)
    )
    (property "Datasheet" "" (at 204.47 277.495 0)
      (effects (font (size 1.27 1.27) (thickness 0.15)) (justify left bottom) hide)
    )
    (property "Author" "Antmicro" (at 204.47 272.415 0)
      (effects (font (size 1.27 1.27) (thickness 0.15)) (justify left bottom) hide)
    )
    (property "License" "Apache-2.0" (at 204.47 274.955 0)
      (effects (font (size 1.27 1.27) (thickness 0.15)) (justify left bottom) hide)
    )
    (pin "1")
    (instances
      (project "kria-k26-devboard"
        (path ""
          (reference "#PWR0375") (unit 1)
        )
      )
    )
  )

  (symbol (lib_id "kria-k26-devboard:GND") (at 233.68 264.795 0) (unit 1)
    (in_bom yes) (on_board yes) (dnp no) (fields_autoplaced)
    (property "Reference" "#PWR0381" (at 233.68 271.145 0)
      (effects (font (size 1.27 1.27)) hide)
    )
    (property "Value" "GND" (at 233.68 269.875 0)
      (effects (font (size 1.27 1.27)))
    )
    (property "Footprint" "" (at 242.57 272.415 0)
      (effects (font (size 1.27 1.27) (thickness 0.15)) (justify left bottom) hide)
    )
    (property "Datasheet" "" (at 242.57 277.495 0)
      (effects (font (size 1.27 1.27) (thickness 0.15)) (justify left bottom) hide)
    )
    (property "Author" "Antmicro" (at 242.57 272.415 0)
      (effects (font (size 1.27 1.27) (thickness 0.15)) (justify left bottom) hide)
    )
    (property "License" "Apache-2.0" (at 242.57 274.955 0)
      (effects (font (size 1.27 1.27) (thickness 0.15)) (justify left bottom) hide)
    )
    (pin "1")
    (instances
      (project "kria-k26-devboard"
        (path ""
          (reference "#PWR0381") (unit 1)
        )
      )
    )
  )

  (symbol (lib_id "kria-k26-devboard:RT6236AHGQUF") (at 57.15 34.29 0) (unit 1)
    (in_bom yes) (on_board yes) (dnp no) (fields_autoplaced)
    (property "Reference" "U47" (at 66.04 26.67 0)
      (effects (font (size 1.27 1.27)))
    )
    (property "Value" "RT6236AHGQUF" (at 66.04 29.21 0)
      (effects (font (size 1.27 1.27) (thickness 0.15)))
    )
    (property "Footprint" "kria-k26-devboard-footprints:UQFN-13_2x3mm_P0.5mm" (at 90.17 41.91 0)
      (effects (font (size 1.27 1.27) (thickness 0.15)) (justify left bottom) hide)
    )
    (property "Datasheet" "https://www.richtek.com/assets/product_file/RT6236A=RT6236B/DS6236AB-02.pdf" (at 90.17 44.45 0)
      (effects (font (size 1.27 1.27) (thickness 0.15)) (justify left bottom) hide)
    )
    (property "MPN" "RT6236AHGQUF" (at 90.17 46.99 0)
      (effects (font (size 1.27 1.27) (thickness 0.15)) (justify left bottom) hide)
    )
    (property "Manufacturer" "Richtek" (at 90.17 49.53 0)
      (effects (font (size 1.27 1.27) (thickness 0.15)) (justify left bottom) hide)
    )
    (property "Author" "Antmicro" (at 90.17 52.07 0)
      (effects (font (size 1.27 1.27) (thickness 0.15)) (justify left bottom) hide)
    )
    (property "License" "Apache-2.0" (at 90.17 54.61 0)
      (effects (font (size 1.27 1.27) (thickness 0.15)) (justify left bottom) hide)
    )
    (pin "1")
    (pin "10")
    (pin "11")
    (pin "12")
    (pin "13")
    (pin "2")
    (pin "3")
    (pin "4")
    (pin "5")
    (pin "6")
    (pin "7")
    (pin "8")
    (pin "9")
    (instances
      (project "kria-k26-devboard"
        (path ""
          (reference "U47") (unit 1)
        )
      )
    )
  )

  (symbol (lib_id "kria-k26-devboard:C_1u_0402") (at 44.45 49.53 270) (unit 1)
    (in_bom yes) (on_board yes) (dnp no)
    (property "Reference" "C187" (at 43.815 50.165 90)
      (effects (font (size 1.524 1.524)) (justify right))
    )
    (property "Value" "C_1u_0402" (at 40.64 49.53 0)
      (effects (font (size 1.524 1.524)) hide)
    )
    (property "Footprint" "kria-k26-devboard-footprints:C_0402_1005Metric" (at 49.53 54.61 0)
      (effects (font (size 1.27 1.27) (thickness 0.15)) (justify left bottom) hide)
    )
    (property "Datasheet" " " (at 44.45 49.53 0)
      (effects (font (size 1.27 1.27) (thickness 0.15)) (justify left bottom) hide)
    )
    (property "Manufacturer" "TDK" (at 54.61 54.61 0)
      (effects (font (size 1.27 1.27) (thickness 0.15)) (justify left bottom) hide)
    )
    (property "MPN" "C1005X6S1A105K050BC" (at 52.07 54.61 0)
      (effects (font (size 1.27 1.27) (thickness 0.15)) (justify left bottom) hide)
    )
    (property "Val" "1u" (at 43.815 53.975 90)
      (effects (font (size 1.27 1.27) (thickness 0.15)) (justify right))
    )
    (property "License" "Apache-2.0" (at 21.59 69.85 0)
      (effects (font (size 1.27 1.27) (thickness 0.15)) (justify left bottom) hide)
    )
    (property "Author" "Antmicro" (at 19.05 69.85 0)
      (effects (font (size 1.27 1.27) (thickness 0.15)) (justify left bottom) hide)
    )
    (property "Voltage" "" (at 16.51 69.85 0)
      (effects (font (size 1.27 1.27)) (justify left bottom) hide)
    )
    (property "Dielectric" "" (at 13.97 69.85 0)
      (effects (font (size 1.27 1.27)) (justify left bottom) hide)
    )
    (pin "1")
    (pin "2")
    (instances
      (project "kria-k26-devboard"
        (path ""
          (reference "C187") (unit 1)
        )
      )
    )
  )

  (symbol (lib_id "kria-k26-devboard:C_3n9_0402") (at 48.26 49.53 270) (unit 1)
    (in_bom yes) (on_board yes) (dnp no)
    (property "Reference" "C189" (at 48.895 50.165 90)
      (effects (font (size 1.524 1.524)) (justify left))
    )
    (property "Value" "C_3n9_0402" (at 44.45 49.53 0)
      (effects (font (size 1.524 1.524)) hide)
    )
    (property "Footprint" "kria-k26-devboard-footprints:C_0402_1005Metric" (at 53.34 54.61 0)
      (effects (font (size 1.27 1.27) (thickness 0.15)) (justify left bottom) hide)
    )
    (property "Datasheet" " " (at 48.26 49.53 0)
      (effects (font (size 1.27 1.27) (thickness 0.15)) (justify left bottom) hide)
    )
    (property "Manufacturer" "Murata" (at 58.42 54.61 0)
      (effects (font (size 1.27 1.27) (thickness 0.15)) (justify left bottom) hide)
    )
    (property "MPN" "GRM155R71H392KA01D" (at 55.88 54.61 0)
      (effects (font (size 1.27 1.27) (thickness 0.15)) (justify left bottom) hide)
    )
    (property "Val" "3n9" (at 48.895 53.975 90)
      (effects (font (size 1.27 1.27) (thickness 0.15)) (justify left))
    )
    (property "License" "Apache-2.0" (at 25.4 69.85 0)
      (effects (font (size 1.27 1.27) (thickness 0.15)) (justify left bottom) hide)
    )
    (property "Author" "Antmicro" (at 22.86 69.85 0)
      (effects (font (size 1.27 1.27) (thickness 0.15)) (justify left bottom) hide)
    )
    (property "Voltage" "" (at 20.32 69.85 0)
      (effects (font (size 1.27 1.27)) (justify left bottom) hide)
    )
    (property "Dielectric" "" (at 17.78 69.85 0)
      (effects (font (size 1.27 1.27)) (justify left bottom) hide)
    )
    (pin "1")
    (pin "2")
    (instances
      (project "kria-k26-devboard"
        (path ""
          (reference "C189") (unit 1)
        )
      )
    )
  )

  (symbol (lib_id "kria-k26-devboard:C_10u_25V_0603") (at 33.02 36.195 270) (unit 1)
    (in_bom yes) (on_board yes) (dnp no) (fields_autoplaced)
    (property "Reference" "C185" (at 35.56 37.4713 90)
      (effects (font (size 1.524 1.524)) (justify left))
    )
    (property "Value" "C_10u_25V_0603" (at 29.21 36.195 0)
      (effects (font (size 1.524 1.524)) hide)
    )
    (property "Footprint" "kria-k26-devboard-footprints:C_0603_1608Metric" (at 38.1 41.275 0)
      (effects (font (size 1.27 1.27) (thickness 0.15)) (justify left bottom) hide)
    )
    (property "Datasheet" " " (at 33.02 36.195 0)
      (effects (font (size 1.27 1.27) (thickness 0.15)) (justify left bottom) hide)
    )
    (property "Manufacturer" "TDK" (at 43.18 41.275 0)
      (effects (font (size 1.27 1.27) (thickness 0.15)) (justify left bottom) hide)
    )
    (property "MPN" "C1608X5R1E106M080AC" (at 40.64 41.275 0)
      (effects (font (size 1.27 1.27) (thickness 0.15)) (justify left bottom) hide)
    )
    (property "Val" "10u/25V" (at 35.56 40.6462 90)
      (effects (font (size 1.27 1.27) (thickness 0.15)) (justify left))
    )
    (property "License" "Apache-2.0" (at 10.16 56.515 0)
      (effects (font (size 1.27 1.27) (thickness 0.15)) (justify left bottom) hide)
    )
    (property "Author" "Antmicro" (at 7.62 56.515 0)
      (effects (font (size 1.27 1.27) (thickness 0.15)) (justify left bottom) hide)
    )
    (property "Voltage" "" (at 5.08 56.515 0)
      (effects (font (size 1.27 1.27)) (justify left bottom) hide)
    )
    (property "Dielectric" "" (at 2.54 56.515 0)
      (effects (font (size 1.27 1.27)) (justify left bottom) hide)
    )
    (pin "1")
    (pin "2")
    (instances
      (project "kria-k26-devboard"
        (path ""
          (reference "C185") (unit 1)
        )
      )
    )
  )

  (symbol (lib_id "kria-k26-devboard:C_10u_25V_0603") (at 29.21 36.195 270) (unit 1)
    (in_bom yes) (on_board yes) (dnp no) (fields_autoplaced)
    (property "Reference" "C183" (at 26.035 37.4713 90)
      (effects (font (size 1.524 1.524)) (justify right))
    )
    (property "Value" "C_10u_25V_0603" (at 25.4 36.195 0)
      (effects (font (size 1.524 1.524)) hide)
    )
    (property "Footprint" "kria-k26-devboard-footprints:C_0603_1608Metric" (at 34.29 41.275 0)
      (effects (font (size 1.27 1.27) (thickness 0.15)) (justify left bottom) hide)
    )
    (property "Datasheet" " " (at 29.21 36.195 0)
      (effects (font (size 1.27 1.27) (thickness 0.15)) (justify left bottom) hide)
    )
    (property "Manufacturer" "TDK" (at 39.37 41.275 0)
      (effects (font (size 1.27 1.27) (thickness 0.15)) (justify left bottom) hide)
    )
    (property "MPN" "C1608X5R1E106M080AC" (at 36.83 41.275 0)
      (effects (font (size 1.27 1.27) (thickness 0.15)) (justify left bottom) hide)
    )
    (property "Val" "10u/25V" (at 26.035 40.6462 90)
      (effects (font (size 1.27 1.27) (thickness 0.15)) (justify right))
    )
    (property "License" "Apache-2.0" (at 6.35 56.515 0)
      (effects (font (size 1.27 1.27) (thickness 0.15)) (justify left bottom) hide)
    )
    (property "Author" "Antmicro" (at 3.81 56.515 0)
      (effects (font (size 1.27 1.27) (thickness 0.15)) (justify left bottom) hide)
    )
    (property "Voltage" "" (at 1.27 56.515 0)
      (effects (font (size 1.27 1.27)) (justify left bottom) hide)
    )
    (property "Dielectric" "" (at -1.27 56.515 0)
      (effects (font (size 1.27 1.27)) (justify left bottom) hide)
    )
    (pin "1")
    (pin "2")
    (instances
      (project "kria-k26-devboard"
        (path ""
          (reference "C183") (unit 1)
        )
      )
    )
  )

  (symbol (lib_id "kria-k26-devboard:C_100n_0402") (at 76.2 41.91 0) (unit 1)
    (in_bom yes) (on_board yes) (dnp no)
    (property "Reference" "C191" (at 82.55 40.64 0)
      (effects (font (size 1.524 1.524)))
    )
    (property "Value" "C_100n_0402" (at 76.2 45.72 0)
      (effects (font (size 1.524 1.524)) hide)
    )
    (property "Footprint" "kria-k26-devboard-footprints:C_0402_1005Metric" (at 81.28 36.83 0)
      (effects (font (size 1.27 1.27) (thickness 0.15)) (justify left bottom) hide)
    )
    (property "Datasheet" "https://search.murata.co.jp/Ceramy/image/img/A01X/G101/ENG/GRM155R61H104KE14-01.pdf" (at 76.2 41.91 0)
      (effects (font (size 1.27 1.27) (thickness 0.15)) (justify left bottom) hide)
    )
    (property "Manufacturer" "Murata" (at 81.28 31.75 0)
      (effects (font (size 1.27 1.27) (thickness 0.15)) (justify left bottom) hide)
    )
    (property "MPN" "GRM155R61H104KE14D" (at 81.28 34.29 0)
      (effects (font (size 1.27 1.27) (thickness 0.15)) (justify left bottom) hide)
    )
    (property "Val" "100n" (at 81.915 43.18 0)
      (effects (font (size 1.27 1.27) (thickness 0.15)))
    )
    (property "License" "Apache-2.0" (at 96.52 64.77 0)
      (effects (font (size 1.27 1.27) (thickness 0.15)) (justify left bottom) hide)
    )
    (property "Author" "Antmicro" (at 96.52 67.31 0)
      (effects (font (size 1.27 1.27) (thickness 0.15)) (justify left bottom) hide)
    )
    (property "Voltage" "50V" (at 96.52 69.85 0)
      (effects (font (size 1.27 1.27)) (justify left bottom) hide)
    )
    (property "Dielectric" "X5R" (at 96.52 72.39 0)
      (effects (font (size 1.27 1.27)) (justify left bottom) hide)
    )
    (pin "1")
    (pin "2")
    (instances
      (project "kria-k26-devboard"
        (path ""
          (reference "C191") (unit 1)
        )
      )
    )
  )

  (symbol (lib_id "kria-k26-devboard:L_3u3_6.6A_XEL4030") (at 89.535 38.1 0) (unit 1)
    (in_bom yes) (on_board yes) (dnp no) (fields_autoplaced)
    (property "Reference" "L1" (at 92.075 33.02 0)
      (effects (font (size 1.27 1.27)))
    )
    (property "Value" "L_3u3_5.9A_XEL4030" (at 92.075 33.02 0)
      (effects (font (size 1.27 1.27)) hide)
    )
    (property "Footprint" "kria-k26-devboard-footprints:L_Coilcraft-XEL4030" (at 109.855 31.75 0)
      (effects (font (size 1.27 1.27) (thickness 0.15)) (justify left bottom) hide)
    )
    (property "Datasheet" "https://www.coilcraft.com/getmedia/8245f050-f190-4295-8c41-7c03d662ee3d/xel4030.pdf" (at 90.932 37.338 0)
      (effects (font (size 1.27 1.27) (thickness 0.15)) (justify left bottom) hide)
    )
    (property "MPN" "XEL4030-332MEC" (at 94.615 25.4 0)
      (effects (font (size 1.27 1.27) (thickness 0.15)) (justify left bottom) hide)
    )
    (property "Manufacturer" "Coilcraft" (at 97.155 22.86 0)
      (effects (font (size 1.27 1.27) (thickness 0.15)) (justify left bottom) hide)
    )
    (property "Val" "3u3/5.9A" (at 92.075 35.56 0)
      (effects (font (size 1.27 1.27) (thickness 0.15)))
    )
    (property "Size" "4x4" (at 92.71 29.845 0)
      (effects (font (size 1.27 1.27) (thickness 0.15)) (justify left bottom) hide)
    )
    (property "ISat" "" (at 103.505 54.61 0)
      (effects (font (size 1.27 1.27)) (justify left) hide)
    )
    (property "IMax" "" (at 103.505 58.42 0)
      (effects (font (size 1.27 1.27) (thickness 0.15)) (justify left bottom) hide)
    )
    (property "Author" "Antmicro" (at 103.505 63.5 0)
      (effects (font (size 1.27 1.27) (thickness 0.15)) (justify left bottom) hide)
    )
    (property "License" "Apache-2.0" (at 103.505 66.04 0)
      (effects (font (size 1.27 1.27) (thickness 0.15)) (justify left bottom) hide)
    )
    (pin "1")
    (pin "2")
    (instances
      (project "kria-k26-devboard"
        (path ""
          (reference "L1") (unit 1)
        )
      )
    )
  )

  (symbol (lib_id "kria-k26-devboard:R_24k_0402") (at 97.155 50.8 270) (unit 1)
    (in_bom yes) (on_board yes) (dnp no) (fields_autoplaced)
    (property "Reference" "R123" (at 99.695 52.07 90)
      (effects (font (size 1.524 1.524)) (justify left))
    )
    (property "Value" "R_24k_0402" (at 93.345 50.8 0)
      (effects (font (size 1.524 1.524)) hide)
    )
    (property "Footprint" "kria-k26-devboard-footprints:R_0402_1005Metric" (at 102.235 55.88 0)
      (effects (font (size 1.27 1.27) (thickness 0.15)) (justify left bottom) hide)
    )
    (property "Datasheet" "https://www.bourns.com/docs/product-datasheets/cr.pdf" (at 97.155 50.8 0)
      (effects (font (size 1.27 1.27) (thickness 0.15)) (justify left bottom) hide)
    )
    (property "Manufacturer" "Bourns" (at 107.315 55.88 0)
      (effects (font (size 1.27 1.27) (thickness 0.15)) (justify left bottom) hide)
    )
    (property "MPN" "CR0402-FX-2402GLF" (at 104.775 55.88 0)
      (effects (font (size 1.27 1.27) (thickness 0.15)) (justify left bottom) hide)
    )
    (property "Val" "24k" (at 99.695 55.2449 90)
      (effects (font (size 1.27 1.27) (thickness 0.15)) (justify left))
    )
    (property "License" "Apache-2.0" (at 71.755 71.12 0)
      (effects (font (size 1.27 1.27) (thickness 0.15)) (justify left bottom) hide)
    )
    (property "Author" "Antmicro" (at 69.215 71.12 0)
      (effects (font (size 1.27 1.27) (thickness 0.15)) (justify left bottom) hide)
    )
    (property "Tolerance" "1%" (at 86.995 71.12 0)
      (effects (font (size 1.27 1.27)) (justify left bottom) hide)
    )
    (pin "1")
    (pin "2")
    (instances
      (project "kria-k26-devboard"
        (path ""
          (reference "R123") (unit 1)
        )
      )
    )
  )

  (symbol (lib_id "kria-k26-devboard:C_22p_0402") (at 88.9 48.26 90) (unit 1)
    (in_bom yes) (on_board yes) (dnp no)
    (property "Reference" "C193" (at 89.535 43.815 90)
      (effects (font (size 1.524 1.524)) (justify right))
    )
    (property "Value" "C_22p_0402" (at 92.71 48.26 0)
      (effects (font (size 1.524 1.524)) hide)
    )
    (property "Footprint" "kria-k26-devboard-footprints:C_0402_1005Metric" (at 83.82 43.18 0)
      (effects (font (size 1.27 1.27) (thickness 0.15)) (justify left bottom) hide)
    )
    (property "Datasheet" " " (at 88.9 48.26 0)
      (effects (font (size 1.27 1.27) (thickness 0.15)) (justify left bottom) hide)
    )
    (property "Manufacturer" "Yaego" (at 78.74 43.18 0)
      (effects (font (size 1.27 1.27) (thickness 0.15)) (justify left bottom) hide)
    )
    (property "MPN" "CC0402JRNPO9BN220" (at 81.28 43.18 0)
      (effects (font (size 1.27 1.27) (thickness 0.15)) (justify left bottom) hide)
    )
    (property "Val" "22p" (at 89.535 47.625 90)
      (effects (font (size 1.27 1.27) (thickness 0.15)) (justify right))
    )
    (property "License" "Apache-2.0" (at 111.76 27.94 0)
      (effects (font (size 1.27 1.27) (thickness 0.15)) (justify left bottom) hide)
    )
    (property "Author" "Antmicro" (at 114.3 27.94 0)
      (effects (font (size 1.27 1.27) (thickness 0.15)) (justify left bottom) hide)
    )
    (property "Voltage" "" (at 116.84 27.94 0)
      (effects (font (size 1.27 1.27)) (justify left bottom) hide)
    )
    (property "Dielectric" "" (at 119.38 27.94 0)
      (effects (font (size 1.27 1.27)) (justify left bottom) hide)
    )
    (pin "1")
    (pin "2")
    (instances
      (project "kria-k26-devboard"
        (path ""
          (reference "C193") (unit 1)
        )
      )
    )
  )

  (symbol (lib_id "kria-k26-devboard:R_100k_0402") (at 50.165 38.1 180) (unit 1)
    (in_bom yes) (on_board yes) (dnp no)
    (property "Reference" "R118" (at 52.705 36.83 0)
      (effects (font (size 1.524 1.524)))
    )
    (property "Value" "R_100k_0402" (at 50.165 34.29 0)
      (effects (font (size 1.524 1.524)) hide)
    )
    (property "Footprint" "kria-k26-devboard-footprints:R_0402_1005Metric" (at 45.085 43.18 0)
      (effects (font (size 1.27 1.27) (thickness 0.15)) (justify left bottom) hide)
    )
    (property "Datasheet" "https://www.bourns.com/docs/product-datasheets/cr.pdf" (at 50.165 38.1 0)
      (effects (font (size 1.27 1.27) (thickness 0.15)) (justify left bottom) hide)
    )
    (property "Manufacturer" "Bourns" (at 45.085 48.26 0)
      (effects (font (size 1.27 1.27) (thickness 0.15)) (justify left bottom) hide)
    )
    (property "MPN" "CR0402-FX-1003GLF" (at 45.085 45.72 0)
      (effects (font (size 1.27 1.27) (thickness 0.15)) (justify left bottom) hide)
    )
    (property "Val" "100k" (at 52.705 39.37 0)
      (effects (font (size 1.27 1.27) (thickness 0.15)))
    )
    (property "License" "Apache-2.0" (at 29.845 12.7 0)
      (effects (font (size 1.27 1.27) (thickness 0.15)) (justify left bottom) hide)
    )
    (property "Author" "Antmicro" (at 29.845 10.16 0)
      (effects (font (size 1.27 1.27) (thickness 0.15)) (justify left bottom) hide)
    )
    (property "Tolerance" "1%" (at 29.845 27.94 0)
      (effects (font (size 1.27 1.27)) (justify left bottom) hide)
    )
    (pin "1")
    (pin "2")
    (instances
      (project "kria-k26-devboard"
        (path ""
          (reference "R118") (unit 1)
        )
      )
    )
  )

  (symbol (lib_id "kria-k26-devboard:R_0R_0402") (at 163.195 77.47 0) (unit 1)
    (in_bom yes) (on_board yes) (dnp no)
    (property "Reference" "R127" (at 165.735 72.39 0)
      (effects (font (size 1.524 1.524)))
    )
    (property "Value" "R_0R_0402" (at 163.195 81.28 0)
      (effects (font (size 1.524 1.524)) hide)
    )
    (property "Footprint" "kria-k26-devboard-footprints:R_0402_1005Metric" (at 168.275 72.39 0)
      (effects (font (size 1.27 1.27) (thickness 0.15)) (justify left bottom) hide)
    )
    (property "Datasheet" "https://industrial.panasonic.com/cdbs/www-data/pdf/RDA0000/AOA0000C301.pdf" (at 163.195 77.47 0)
      (effects (font (size 1.27 1.27) (thickness 0.15)) (justify left bottom) hide)
    )
    (property "Manufacturer" "Panasonic" (at 168.275 67.31 0)
      (effects (font (size 1.27 1.27) (thickness 0.15)) (justify left bottom) hide)
    )
    (property "MPN" "ERJ2GE0R00X" (at 168.275 69.85 0)
      (effects (font (size 1.27 1.27) (thickness 0.15)) (justify left bottom) hide)
    )
    (property "Val" "0R" (at 165.735 74.93 0)
      (effects (font (size 1.27 1.27) (thickness 0.15)))
    )
    (property "License" "Apache-2.0" (at 183.515 102.87 0)
      (effects (font (size 1.27 1.27) (thickness 0.15)) (justify left bottom) hide)
    )
    (property "Author" "Antmicro" (at 183.515 105.41 0)
      (effects (font (size 1.27 1.27) (thickness 0.15)) (justify left bottom) hide)
    )
    (property "Tolerance" "~" (at 183.515 87.63 0)
      (effects (font (size 1.27 1.27)) (justify left bottom) hide)
    )
    (property "Current" "1A" (at 183.515 107.95 0)
      (effects (font (size 1.27 1.27) (thickness 0.15)) (justify left bottom) hide)
    )
    (pin "1")
    (pin "2")
    (instances
      (project "kria-k26-devboard"
        (path ""
          (reference "R127") (unit 1)
        )
      )
    )
  )

  (symbol (lib_id "kria-k26-devboard:R_1k_0402") (at 267.97 241.935 0) (unit 1)
    (in_bom yes) (on_board yes) (dnp no)
    (property "Reference" "R143" (at 270.51 236.855 0)
      (effects (font (size 1.524 1.524)))
    )
    (property "Value" "R_1k_0402" (at 267.97 245.745 0)
      (effects (font (size 1.27 1.27) (thickness 0.15)) (justify left bottom) hide)
    )
    (property "Footprint" "kria-k26-devboard-footprints:R_0402_1005Metric" (at 273.05 236.855 0)
      (effects (font (size 1.27 1.27) (thickness 0.15)) (justify left bottom) hide)
    )
    (property "Datasheet" "https://www.bourns.com/docs/product-datasheets/cr.pdf" (at 267.97 241.935 0)
      (effects (font (size 1.27 1.27) (thickness 0.15)) (justify left bottom) hide)
    )
    (property "Manufacturer" "Bourns" (at 273.05 231.775 0)
      (effects (font (size 1.27 1.27) (thickness 0.15)) (justify left bottom) hide)
    )
    (property "MPN" "CR0402-FX-1001GLF" (at 273.05 234.315 0)
      (effects (font (size 1.27 1.27) (thickness 0.15)) (justify left bottom) hide)
    )
    (property "Val" "1k" (at 270.51 239.395 0)
      (effects (font (size 1.27 1.27) (thickness 0.15)))
    )
    (property "License" "Apache-2.0" (at 288.29 267.335 0)
      (effects (font (size 1.27 1.27) (thickness 0.15)) (justify left bottom) hide)
    )
    (property "Author" "Antmicro" (at 288.29 269.875 0)
      (effects (font (size 1.27 1.27) (thickness 0.15)) (justify left bottom) hide)
    )
    (property "Tolerance" "1%" (at 288.29 252.095 0)
      (effects (font (size 1.27 1.27)) (justify left bottom) hide)
    )
    (pin "1")
    (pin "2")
    (instances
      (project "kria-k26-devboard"
        (path ""
          (reference "R143") (unit 1)
        )
      )
    )
  )

  (symbol (lib_id "kria-k26-devboard:GND") (at 274.955 264.795 0) (unit 1)
    (in_bom yes) (on_board yes) (dnp no) (fields_autoplaced)
    (property "Reference" "#PWR0385" (at 274.955 271.145 0)
      (effects (font (size 1.27 1.27)) hide)
    )
    (property "Value" "GND" (at 274.955 269.875 0)
      (effects (font (size 1.27 1.27)))
    )
    (property "Footprint" "" (at 283.845 272.415 0)
      (effects (font (size 1.27 1.27) (thickness 0.15)) (justify left bottom) hide)
    )
    (property "Datasheet" "" (at 283.845 277.495 0)
      (effects (font (size 1.27 1.27) (thickness 0.15)) (justify left bottom) hide)
    )
    (property "Author" "Antmicro" (at 283.845 272.415 0)
      (effects (font (size 1.27 1.27) (thickness 0.15)) (justify left bottom) hide)
    )
    (property "License" "Apache-2.0" (at 283.845 274.955 0)
      (effects (font (size 1.27 1.27) (thickness 0.15)) (justify left bottom) hide)
    )
    (pin "1")
    (instances
      (project "kria-k26-devboard"
        (path ""
          (reference "#PWR0385") (unit 1)
        )
      )
    )
  )

  (symbol (lib_id "kria-k26-devboard:LED_G_0603_LG_L29K-G2J1-24-Z") (at 96.52 262.255 0) (unit 1)
    (in_bom yes) (on_board yes) (dnp no)
    (property "Reference" "D19" (at 104.14 260.985 0)
      (effects (font (size 1.524 1.524)))
    )
    (property "Value" "LED_G_0603_LG_L29K-G2J1-24-Z" (at 102.2349 258.445 90)
      (effects (font (size 1.27 1.27) (thickness 0.15)) (justify left) hide)
    )
    (property "Footprint" "kria-k26-devboard-footprints:LED_0603_1608Metric_G" (at 101.6 257.175 0)
      (effects (font (size 1.27 1.27) (thickness 0.15)) (justify left bottom) hide)
    )
    (property "Datasheet" "https://dammedia.osram.info/media/resource/hires/osram-dam-2493945/LG%20L29K.pdf" (at 101.6 254.635 0)
      (effects (font (size 1.27 1.27) (thickness 0.15)) (justify left bottom) hide)
    )
    (property "MPN" "LG L29K-G2J1-24-Z" (at 102.235 263.525 0)
      (effects (font (size 1.27 1.27) (thickness 0.15)) (justify left) hide)
    )
    (property "Manufacturer" "OSRAM" (at 101.6 234.315 0)
      (effects (font (size 1.27 1.27) (thickness 0.15)) (justify left bottom) hide)
    )
    (property "Author" "Antmicro" (at 119.38 282.575 0)
      (effects (font (size 1.27 1.27) (thickness 0.15)) (justify left bottom) hide)
    )
    (property "License" "Apache-2.0" (at 119.38 285.115 0)
      (effects (font (size 1.27 1.27) (thickness 0.15)) (justify left bottom) hide)
    )
    (property "Color" "Green" (at 102.235 264.16 0)
      (effects (font (size 1.27 1.27)) (justify left bottom))
    )
    (pin "1")
    (pin "2")
    (instances
      (project "kria-k26-devboard"
        (path ""
          (reference "D19") (unit 1)
        )
      )
    )
  )

  (symbol (lib_id "kria-k26-devboard:GND") (at 125.095 264.795 0) (unit 1)
    (in_bom yes) (on_board yes) (dnp no) (fields_autoplaced)
    (property "Reference" "#PWR0384" (at 125.095 271.145 0)
      (effects (font (size 1.27 1.27)) hide)
    )
    (property "Value" "GND" (at 125.095 269.24 0)
      (effects (font (size 1.27 1.27)))
    )
    (property "Footprint" "" (at 133.985 272.415 0)
      (effects (font (size 1.27 1.27) (thickness 0.15)) (justify left bottom) hide)
    )
    (property "Datasheet" "" (at 133.985 277.495 0)
      (effects (font (size 1.27 1.27) (thickness 0.15)) (justify left bottom) hide)
    )
    (property "Author" "Antmicro" (at 133.985 272.415 0)
      (effects (font (size 1.27 1.27) (thickness 0.15)) (justify left bottom) hide)
    )
    (property "License" "Apache-2.0" (at 133.985 274.955 0)
      (effects (font (size 1.27 1.27) (thickness 0.15)) (justify left bottom) hide)
    )
    (pin "1")
    (instances
      (project "kria-k26-devboard"
        (path ""
          (reference "#PWR0384") (unit 1)
        )
      )
    )
  )

  (symbol (lib_id "kria-k26-devboard:R_1k_0402") (at 90.17 262.255 0) (unit 1)
    (in_bom yes) (on_board yes) (dnp no)
    (property "Reference" "R142" (at 87.63 260.985 0)
      (effects (font (size 1.524 1.524)))
    )
    (property "Value" "R_1k_0402" (at 90.17 266.065 0)
      (effects (font (size 1.27 1.27) (thickness 0.15)) (justify left bottom) hide)
    )
    (property "Footprint" "kria-k26-devboard-footprints:R_0402_1005Metric" (at 95.25 257.175 0)
      (effects (font (size 1.27 1.27) (thickness 0.15)) (justify left bottom) hide)
    )
    (property "Datasheet" "https://www.bourns.com/docs/product-datasheets/cr.pdf" (at 90.17 262.255 0)
      (effects (font (size 1.27 1.27) (thickness 0.15)) (justify left bottom) hide)
    )
    (property "Manufacturer" "Bourns" (at 95.25 252.095 0)
      (effects (font (size 1.27 1.27) (thickness 0.15)) (justify left bottom) hide)
    )
    (property "MPN" "CR0402-FX-1001GLF" (at 95.25 254.635 0)
      (effects (font (size 1.27 1.27) (thickness 0.15)) (justify left bottom) hide)
    )
    (property "Val" "1k" (at 88.265 263.525 0)
      (effects (font (size 1.27 1.27) (thickness 0.15)))
    )
    (property "License" "Apache-2.0" (at 110.49 287.655 0)
      (effects (font (size 1.27 1.27) (thickness 0.15)) (justify left bottom) hide)
    )
    (property "Author" "Antmicro" (at 110.49 290.195 0)
      (effects (font (size 1.27 1.27) (thickness 0.15)) (justify left bottom) hide)
    )
    (property "Tolerance" "1%" (at 110.49 272.415 0)
      (effects (font (size 1.27 1.27)) (justify left bottom) hide)
    )
    (pin "1")
    (pin "2")
    (instances
      (project "kria-k26-devboard"
        (path ""
          (reference "R142") (unit 1)
        )
      )
    )
  )

  (symbol (lib_id "kria-k26-devboard:LED_G_0603_LG_L29K-G2J1-24-Z") (at 96.52 245.11 0) (unit 1)
    (in_bom yes) (on_board yes) (dnp no)
    (property "Reference" "D13" (at 104.14 243.84 0)
      (effects (font (size 1.524 1.524)))
    )
    (property "Value" "LED_G_0603_LG_L29K-G2J1-24-Z" (at 102.2349 241.935 90)
      (effects (font (size 1.27 1.27) (thickness 0.15)) (justify left) hide)
    )
    (property "Footprint" "kria-k26-devboard-footprints:LED_0603_1608Metric_G" (at 101.6 240.03 0)
      (effects (font (size 1.27 1.27) (thickness 0.15)) (justify left bottom) hide)
    )
    (property "Datasheet" "https://dammedia.osram.info/media/resource/hires/osram-dam-2493945/LG%20L29K.pdf" (at 101.6 237.49 0)
      (effects (font (size 1.27 1.27) (thickness 0.15)) (justify left bottom) hide)
    )
    (property "MPN" "LG L29K-G2J1-24-Z" (at 102.235 246.38 0)
      (effects (font (size 1.27 1.27) (thickness 0.15)) (justify left) hide)
    )
    (property "Manufacturer" "OSRAM" (at 101.6 217.17 0)
      (effects (font (size 1.27 1.27) (thickness 0.15)) (justify left bottom) hide)
    )
    (property "Author" "Antmicro" (at 119.38 265.43 0)
      (effects (font (size 1.27 1.27) (thickness 0.15)) (justify left bottom) hide)
    )
    (property "License" "Apache-2.0" (at 119.38 267.97 0)
      (effects (font (size 1.27 1.27) (thickness 0.15)) (justify left bottom) hide)
    )
    (property "Color" "Green" (at 102.235 247.015 0)
      (effects (font (size 1.27 1.27)) (justify left bottom))
    )
    (pin "1")
    (pin "2")
    (instances
      (project "kria-k26-devboard"
        (path ""
          (reference "D13") (unit 1)
        )
      )
    )
  )

  (symbol (lib_id "kria-k26-devboard:L_1u_2.5A_0805") (at 230.505 72.39 0) (unit 1)
    (in_bom yes) (on_board yes) (dnp no)
    (property "Reference" "L4" (at 233.045 67.945 0)
      (effects (font (size 1.524 1.524)))
    )
    (property "Value" "L_1u_2.5A_0805" (at 233.045 66.04 0)
      (effects (font (size 1.524 1.524)) hide)
    )
    (property "Footprint" "kria-k26-devboard-footprints:L_0805_2012Metric" (at 246.38 63.5 0)
      (effects (font (size 1.27 1.27) (thickness 0.15)) (justify left bottom) hide)
    )
    (property "Datasheet" "https://product.tdk.com/system/files/dam/doc/product/inductor/inductor/smd/catalog/inductor_commercial_power_tfm201208ald_en.pdf" (at 231.902 71.628 0)
      (effects (font (size 1.27 1.27) (thickness 0.15)) (justify left bottom) hide)
    )
    (property "Manufacturer" "TDK" (at 234.315 53.34 0)
      (effects (font (size 1.27 1.27) (thickness 0.15)) (justify left bottom) hide)
    )
    (property "MPN" "TFM201208ALD-1R0MTCA" (at 238.125 55.88 0)
      (effects (font (size 1.27 1.27) (thickness 0.15)) (justify left bottom) hide)
    )
    (property "Size" "1.25x0.8" (at 233.68 60.96 0)
      (effects (font (size 1.27 1.27) (thickness 0.15)) (justify left bottom) hide)
    )
    (property "Val" "1u/2.5A" (at 233.045 69.85 0)
      (effects (font (size 1.27 1.27) (thickness 0.15)))
    )
    (property "ISat" "" (at 244.475 88.9 0)
      (effects (font (size 1.27 1.27)) (justify left) hide)
    )
    (property "IMax" "" (at 244.475 92.71 0)
      (effects (font (size 1.27 1.27) (thickness 0.15)) (justify left bottom) hide)
    )
    (property "Author" "Antmicro" (at 244.475 97.79 0)
      (effects (font (size 1.27 1.27) (thickness 0.15)) (justify left bottom) hide)
    )
    (property "License" "Apache-2.0" (at 244.475 100.33 0)
      (effects (font (size 1.27 1.27) (thickness 0.15)) (justify left bottom) hide)
    )
    (pin "1")
    (pin "2")
    (instances
      (project "kria-k26-devboard"
        (path ""
          (reference "L4") (unit 1)
        )
      )
    )
  )

  (symbol (lib_id "kria-k26-devboard:L_1u_2.5A_0805") (at 231.14 193.04 0) (unit 1)
    (in_bom yes) (on_board yes) (dnp no)
    (property "Reference" "L7" (at 233.68 187.96 0)
      (effects (font (size 1.524 1.524)))
    )
    (property "Value" "L_1u_2.5A_0805" (at 233.68 186.69 0)
      (effects (font (size 1.524 1.524)) hide)
    )
    (property "Footprint" "kria-k26-devboard-footprints:L_0805_2012Metric" (at 247.015 184.15 0)
      (effects (font (size 1.27 1.27) (thickness 0.15)) (justify left bottom) hide)
    )
    (property "Datasheet" "https://product.tdk.com/system/files/dam/doc/product/inductor/inductor/smd/catalog/inductor_commercial_power_tfm201208ald_en.pdf" (at 232.537 192.278 0)
      (effects (font (size 1.27 1.27) (thickness 0.15)) (justify left bottom) hide)
    )
    (property "Manufacturer" "TDK" (at 234.95 173.99 0)
      (effects (font (size 1.27 1.27) (thickness 0.15)) (justify left bottom) hide)
    )
    (property "MPN" "TFM201208ALD-1R0MTCA" (at 238.76 176.53 0)
      (effects (font (size 1.27 1.27) (thickness 0.15)) (justify left bottom) hide)
    )
    (property "Size" "1.25x0.8" (at 234.315 181.61 0)
      (effects (font (size 1.27 1.27) (thickness 0.15)) (justify left bottom) hide)
    )
    (property "Val" "1u/2.5A" (at 233.68 190.5 0)
      (effects (font (size 1.27 1.27) (thickness 0.15)))
    )
    (property "ISat" "" (at 245.11 209.55 0)
      (effects (font (size 1.27 1.27)) (justify left) hide)
    )
    (property "IMax" "" (at 245.11 213.36 0)
      (effects (font (size 1.27 1.27) (thickness 0.15)) (justify left bottom) hide)
    )
    (property "Author" "Antmicro" (at 245.11 218.44 0)
      (effects (font (size 1.27 1.27) (thickness 0.15)) (justify left bottom) hide)
    )
    (property "License" "Apache-2.0" (at 245.11 220.98 0)
      (effects (font (size 1.27 1.27) (thickness 0.15)) (justify left bottom) hide)
    )
    (pin "1")
    (pin "2")
    (instances
      (project "kria-k26-devboard"
        (path ""
          (reference "L7") (unit 1)
        )
      )
    )
  )

  (symbol (lib_id "kria-k26-devboard:TP_0.75mm_SMD") (at 247.65 33.02 90) (unit 1)
    (in_bom yes) (on_board yes) (dnp no) (fields_autoplaced)
    (property "Reference" "TP36" (at 249.555 29.8449 90)
      (effects (font (size 1.27 1.27)) (justify right))
    )
    (property "Value" "TP_0.75mm_SMD" (at 250.19 33.02 0)
      (effects (font (size 1.27 1.27) (thickness 0.15)) (justify left bottom) hide)
    )
    (property "Footprint" "kria-k26-devboard-footprints:TP_SMD_0.75mm" (at 242.57 27.94 0)
      (effects (font (size 1.27 1.27) (thickness 0.15)) (justify left bottom) hide)
    )
    (property "Datasheet" "" (at 240.03 27.94 0)
      (effects (font (size 1.27 1.27) (thickness 0.15)) (justify left bottom) hide)
    )
    (property "MPN" "" (at 247.65 33.02 0)
      (effects (font (size 1.27 1.27) (thickness 0.15)) (justify left bottom) hide)
    )
    (property "Manufacturer" "" (at 247.65 33.02 0)
      (effects (font (size 1.27 1.27) (thickness 0.15)) (justify left bottom) hide)
    )
    (property "Author" "Antmicro" (at 262.89 17.78 0)
      (effects (font (size 1.27 1.27) (thickness 0.15)) (justify left bottom) hide)
    )
    (property "License" "Apache-2.0" (at 265.43 17.78 0)
      (effects (font (size 1.27 1.27) (thickness 0.15)) (justify left bottom) hide)
    )
    (pin "1")
    (instances
      (project "kria-k26-devboard"
        (path ""
          (reference "TP36") (unit 1)
        )
      )
    )
  )

  (symbol (lib_id "kria-k26-devboard:TP_0.75mm_SMD") (at 243.205 71.12 270) (mirror x) (unit 1)
    (in_bom yes) (on_board yes) (dnp no) (fields_autoplaced)
    (property "Reference" "TP37" (at 245.11 67.9449 90)
      (effects (font (size 1.27 1.27)) (justify left))
    )
    (property "Value" "TP_0.75mm_SMD" (at 240.665 71.12 0)
      (effects (font (size 1.27 1.27) (thickness 0.15)) (justify left bottom) hide)
    )
    (property "Footprint" "kria-k26-devboard-footprints:TP_SMD_0.75mm" (at 248.285 66.04 0)
      (effects (font (size 1.27 1.27) (thickness 0.15)) (justify left bottom) hide)
    )
    (property "Datasheet" "" (at 250.825 66.04 0)
      (effects (font (size 1.27 1.27) (thickness 0.15)) (justify left bottom) hide)
    )
    (property "MPN" "" (at 243.205 71.12 0)
      (effects (font (size 1.27 1.27) (thickness 0.15)) (justify left bottom) hide)
    )
    (property "Manufacturer" "" (at 243.205 71.12 0)
      (effects (font (size 1.27 1.27) (thickness 0.15)) (justify left bottom) hide)
    )
    (property "Author" "Antmicro" (at 227.965 55.88 0)
      (effects (font (size 1.27 1.27) (thickness 0.15)) (justify left bottom) hide)
    )
    (property "License" "Apache-2.0" (at 225.425 55.88 0)
      (effects (font (size 1.27 1.27) (thickness 0.15)) (justify left bottom) hide)
    )
    (pin "1")
    (instances
      (project "kria-k26-devboard"
        (path ""
          (reference "TP37") (unit 1)
        )
      )
    )
  )

  (symbol (lib_id "kria-k26-devboard:TP_0.75mm_SMD") (at 242.57 111.76 90) (unit 1)
    (in_bom yes) (on_board yes) (dnp no) (fields_autoplaced)
    (property "Reference" "TP38" (at 245.11 108.5849 90)
      (effects (font (size 1.27 1.27)) (justify right))
    )
    (property "Value" "TP_0.75mm_SMD" (at 245.11 111.76 0)
      (effects (font (size 1.27 1.27) (thickness 0.15)) (justify left bottom) hide)
    )
    (property "Footprint" "kria-k26-devboard-footprints:TP_SMD_0.75mm" (at 237.49 106.68 0)
      (effects (font (size 1.27 1.27) (thickness 0.15)) (justify left bottom) hide)
    )
    (property "Datasheet" "" (at 234.95 106.68 0)
      (effects (font (size 1.27 1.27) (thickness 0.15)) (justify left bottom) hide)
    )
    (property "MPN" "" (at 242.57 111.76 0)
      (effects (font (size 1.27 1.27) (thickness 0.15)) (justify left bottom) hide)
    )
    (property "Manufacturer" "" (at 242.57 111.76 0)
      (effects (font (size 1.27 1.27) (thickness 0.15)) (justify left bottom) hide)
    )
    (property "Author" "Antmicro" (at 257.81 96.52 0)
      (effects (font (size 1.27 1.27) (thickness 0.15)) (justify left bottom) hide)
    )
    (property "License" "Apache-2.0" (at 260.35 96.52 0)
      (effects (font (size 1.27 1.27) (thickness 0.15)) (justify left bottom) hide)
    )
    (pin "1")
    (instances
      (project "kria-k26-devboard"
        (path ""
          (reference "TP38") (unit 1)
        )
      )
    )
  )

  (symbol (lib_id "kria-k26-devboard:TP_0.75mm_SMD") (at 241.935 151.13 90) (unit 1)
    (in_bom yes) (on_board yes) (dnp no) (fields_autoplaced)
    (property "Reference" "TP39" (at 243.84 147.9549 90)
      (effects (font (size 1.27 1.27)) (justify right))
    )
    (property "Value" "TP_0.75mm_SMD" (at 244.475 151.13 0)
      (effects (font (size 1.27 1.27) (thickness 0.15)) (justify left bottom) hide)
    )
    (property "Footprint" "kria-k26-devboard-footprints:TP_SMD_0.75mm" (at 236.855 146.05 0)
      (effects (font (size 1.27 1.27) (thickness 0.15)) (justify left bottom) hide)
    )
    (property "Datasheet" "" (at 234.315 146.05 0)
      (effects (font (size 1.27 1.27) (thickness 0.15)) (justify left bottom) hide)
    )
    (property "MPN" "" (at 241.935 151.13 0)
      (effects (font (size 1.27 1.27) (thickness 0.15)) (justify left bottom) hide)
    )
    (property "Manufacturer" "" (at 241.935 151.13 0)
      (effects (font (size 1.27 1.27) (thickness 0.15)) (justify left bottom) hide)
    )
    (property "Author" "Antmicro" (at 257.175 135.89 0)
      (effects (font (size 1.27 1.27) (thickness 0.15)) (justify left bottom) hide)
    )
    (property "License" "Apache-2.0" (at 259.715 135.89 0)
      (effects (font (size 1.27 1.27) (thickness 0.15)) (justify left bottom) hide)
    )
    (pin "1")
    (instances
      (project "kria-k26-devboard"
        (path ""
          (reference "TP39") (unit 1)
        )
      )
    )
  )

  (symbol (lib_id "kria-k26-devboard:TP_0.75mm_SMD") (at 251.46 191.77 270) (mirror x) (unit 1)
    (in_bom yes) (on_board yes) (dnp no)
    (property "Reference" "TP40" (at 248.92 186.055 90)
      (effects (font (size 1.27 1.27)) (justify left))
    )
    (property "Value" "TP_0.75mm_SMD" (at 248.92 191.77 0)
      (effects (font (size 1.27 1.27) (thickness 0.15)) (justify left bottom) hide)
    )
    (property "Footprint" "kria-k26-devboard-footprints:TP_SMD_0.75mm" (at 256.54 186.69 0)
      (effects (font (size 1.27 1.27) (thickness 0.15)) (justify left bottom) hide)
    )
    (property "Datasheet" "" (at 259.08 186.69 0)
      (effects (font (size 1.27 1.27) (thickness 0.15)) (justify left bottom) hide)
    )
    (property "MPN" "" (at 251.46 191.77 0)
      (effects (font (size 1.27 1.27) (thickness 0.15)) (justify left bottom) hide)
    )
    (property "Manufacturer" "" (at 251.46 191.77 0)
      (effects (font (size 1.27 1.27) (thickness 0.15)) (justify left bottom) hide)
    )
    (property "Author" "Antmicro" (at 236.22 176.53 0)
      (effects (font (size 1.27 1.27) (thickness 0.15)) (justify left bottom) hide)
    )
    (property "License" "Apache-2.0" (at 233.68 176.53 0)
      (effects (font (size 1.27 1.27) (thickness 0.15)) (justify left bottom) hide)
    )
    (pin "1")
    (instances
      (project "kria-k26-devboard"
        (path ""
          (reference "TP40") (unit 1)
        )
      )
    )
  )

  (symbol (lib_id "kria-k26-devboard:TP_0.75mm_SMD") (at 370.84 33.02 270) (mirror x) (unit 1)
    (in_bom yes) (on_board yes) (dnp no) (fields_autoplaced)
    (property "Reference" "TP41" (at 373.38 29.8449 90)
      (effects (font (size 1.27 1.27)) (justify left))
    )
    (property "Value" "TP_0.75mm_SMD" (at 368.3 33.02 0)
      (effects (font (size 1.27 1.27) (thickness 0.15)) (justify left bottom) hide)
    )
    (property "Footprint" "kria-k26-devboard-footprints:TP_SMD_0.75mm" (at 375.92 27.94 0)
      (effects (font (size 1.27 1.27) (thickness 0.15)) (justify left bottom) hide)
    )
    (property "Datasheet" "" (at 378.46 27.94 0)
      (effects (font (size 1.27 1.27) (thickness 0.15)) (justify left bottom) hide)
    )
    (property "MPN" "" (at 370.84 33.02 0)
      (effects (font (size 1.27 1.27) (thickness 0.15)) (justify left bottom) hide)
    )
    (property "Manufacturer" "" (at 370.84 33.02 0)
      (effects (font (size 1.27 1.27) (thickness 0.15)) (justify left bottom) hide)
    )
    (property "Author" "Antmicro" (at 355.6 17.78 0)
      (effects (font (size 1.27 1.27) (thickness 0.15)) (justify left bottom) hide)
    )
    (property "License" "Apache-2.0" (at 353.06 17.78 0)
      (effects (font (size 1.27 1.27) (thickness 0.15)) (justify left bottom) hide)
    )
    (pin "1")
    (instances
      (project "kria-k26-devboard"
        (path ""
          (reference "TP41") (unit 1)
        )
      )
    )
  )

  (symbol (lib_id "kria-k26-devboard:TP_0.75mm_SMD") (at 370.84 64.77 270) (mirror x) (unit 1)
    (in_bom yes) (on_board yes) (dnp no) (fields_autoplaced)
    (property "Reference" "TP42" (at 373.38 61.5949 90)
      (effects (font (size 1.27 1.27)) (justify left))
    )
    (property "Value" "TP_0.75mm_SMD" (at 368.3 64.77 0)
      (effects (font (size 1.27 1.27) (thickness 0.15)) (justify left bottom) hide)
    )
    (property "Footprint" "kria-k26-devboard-footprints:TP_SMD_0.75mm" (at 375.92 59.69 0)
      (effects (font (size 1.27 1.27) (thickness 0.15)) (justify left bottom) hide)
    )
    (property "Datasheet" "" (at 378.46 59.69 0)
      (effects (font (size 1.27 1.27) (thickness 0.15)) (justify left bottom) hide)
    )
    (property "MPN" "" (at 370.84 64.77 0)
      (effects (font (size 1.27 1.27) (thickness 0.15)) (justify left bottom) hide)
    )
    (property "Manufacturer" "" (at 370.84 64.77 0)
      (effects (font (size 1.27 1.27) (thickness 0.15)) (justify left bottom) hide)
    )
    (property "Author" "Antmicro" (at 355.6 49.53 0)
      (effects (font (size 1.27 1.27) (thickness 0.15)) (justify left bottom) hide)
    )
    (property "License" "Apache-2.0" (at 353.06 49.53 0)
      (effects (font (size 1.27 1.27) (thickness 0.15)) (justify left bottom) hide)
    )
    (pin "1")
    (instances
      (project "kria-k26-devboard"
        (path ""
          (reference "TP42") (unit 1)
        )
      )
    )
  )

  (symbol (lib_id "kria-k26-devboard:C_1u_0402") (at 44.45 102.235 270) (unit 1)
    (in_bom yes) (on_board yes) (dnp no)
    (property "Reference" "C188" (at 43.815 102.87 90)
      (effects (font (size 1.524 1.524)) (justify right))
    )
    (property "Value" "C_1u_0402" (at 40.64 102.235 0)
      (effects (font (size 1.524 1.524)) hide)
    )
    (property "Footprint" "kria-k26-devboard-footprints:C_0402_1005Metric" (at 49.53 107.315 0)
      (effects (font (size 1.27 1.27) (thickness 0.15)) (justify left bottom) hide)
    )
    (property "Datasheet" " " (at 44.45 102.235 0)
      (effects (font (size 1.27 1.27) (thickness 0.15)) (justify left bottom) hide)
    )
    (property "Manufacturer" "TDK" (at 54.61 107.315 0)
      (effects (font (size 1.27 1.27) (thickness 0.15)) (justify left bottom) hide)
    )
    (property "MPN" "C1005X6S1A105K050BC" (at 52.07 107.315 0)
      (effects (font (size 1.27 1.27) (thickness 0.15)) (justify left bottom) hide)
    )
    (property "Val" "1u" (at 43.815 106.68 90)
      (effects (font (size 1.27 1.27) (thickness 0.15)) (justify right))
    )
    (property "License" "Apache-2.0" (at 21.59 122.555 0)
      (effects (font (size 1.27 1.27) (thickness 0.15)) (justify left bottom) hide)
    )
    (property "Author" "Antmicro" (at 19.05 122.555 0)
      (effects (font (size 1.27 1.27) (thickness 0.15)) (justify left bottom) hide)
    )
    (property "Voltage" "" (at 16.51 122.555 0)
      (effects (font (size 1.27 1.27)) (justify left bottom) hide)
    )
    (property "Dielectric" "" (at 13.97 122.555 0)
      (effects (font (size 1.27 1.27)) (justify left bottom) hide)
    )
    (pin "1")
    (pin "2")
    (instances
      (project "kria-k26-devboard"
        (path ""
          (reference "C188") (unit 1)
        )
      )
    )
  )

  (symbol (lib_id "kria-k26-devboard:C_3n9_0402") (at 48.26 102.235 270) (unit 1)
    (in_bom yes) (on_board yes) (dnp no)
    (property "Reference" "C190" (at 48.895 102.87 90)
      (effects (font (size 1.524 1.524)) (justify left))
    )
    (property "Value" "C_3n9_0402" (at 44.45 102.235 0)
      (effects (font (size 1.524 1.524)) hide)
    )
    (property "Footprint" "kria-k26-devboard-footprints:C_0402_1005Metric" (at 53.34 107.315 0)
      (effects (font (size 1.27 1.27) (thickness 0.15)) (justify left bottom) hide)
    )
    (property "Datasheet" " " (at 48.26 102.235 0)
      (effects (font (size 1.27 1.27) (thickness 0.15)) (justify left bottom) hide)
    )
    (property "Manufacturer" "Murata" (at 58.42 107.315 0)
      (effects (font (size 1.27 1.27) (thickness 0.15)) (justify left bottom) hide)
    )
    (property "MPN" "GRM155R71H392KA01D" (at 55.88 107.315 0)
      (effects (font (size 1.27 1.27) (thickness 0.15)) (justify left bottom) hide)
    )
    (property "Val" "3n9" (at 48.895 106.68 90)
      (effects (font (size 1.27 1.27) (thickness 0.15)) (justify left))
    )
    (property "License" "Apache-2.0" (at 25.4 122.555 0)
      (effects (font (size 1.27 1.27) (thickness 0.15)) (justify left bottom) hide)
    )
    (property "Author" "Antmicro" (at 22.86 122.555 0)
      (effects (font (size 1.27 1.27) (thickness 0.15)) (justify left bottom) hide)
    )
    (property "Voltage" "" (at 20.32 122.555 0)
      (effects (font (size 1.27 1.27)) (justify left bottom) hide)
    )
    (property "Dielectric" "" (at 17.78 122.555 0)
      (effects (font (size 1.27 1.27)) (justify left bottom) hide)
    )
    (pin "1")
    (pin "2")
    (instances
      (project "kria-k26-devboard"
        (path ""
          (reference "C190") (unit 1)
        )
      )
    )
  )

  (symbol (lib_id "kria-k26-devboard:C_10u_25V_0603") (at 33.655 94.615 270) (unit 1)
    (in_bom yes) (on_board yes) (dnp no)
    (property "Reference" "C186" (at 34.29 95.25 90)
      (effects (font (size 1.524 1.524)) (justify left))
    )
    (property "Value" "C_10u_25V_0603" (at 29.845 94.615 0)
      (effects (font (size 1.524 1.524)) hide)
    )
    (property "Footprint" "kria-k26-devboard-footprints:C_0603_1608Metric" (at 38.735 99.695 0)
      (effects (font (size 1.27 1.27) (thickness 0.15)) (justify left bottom) hide)
    )
    (property "Datasheet" " " (at 33.655 94.615 0)
      (effects (font (size 1.27 1.27) (thickness 0.15)) (justify left bottom) hide)
    )
    (property "Manufacturer" "TDK" (at 43.815 99.695 0)
      (effects (font (size 1.27 1.27) (thickness 0.15)) (justify left bottom) hide)
    )
    (property "MPN" "C1608X5R1E106M080AC" (at 41.275 99.695 0)
      (effects (font (size 1.27 1.27) (thickness 0.15)) (justify left bottom) hide)
    )
    (property "Val" "10u/25V" (at 34.29 99.06 90)
      (effects (font (size 1.27 1.27) (thickness 0.15)) (justify left))
    )
    (property "License" "Apache-2.0" (at 10.795 114.935 0)
      (effects (font (size 1.27 1.27) (thickness 0.15)) (justify left bottom) hide)
    )
    (property "Author" "Antmicro" (at 8.255 114.935 0)
      (effects (font (size 1.27 1.27) (thickness 0.15)) (justify left bottom) hide)
    )
    (property "Voltage" "" (at 5.715 114.935 0)
      (effects (font (size 1.27 1.27)) (justify left bottom) hide)
    )
    (property "Dielectric" "" (at 3.175 114.935 0)
      (effects (font (size 1.27 1.27)) (justify left bottom) hide)
    )
    (pin "1")
    (pin "2")
    (instances
      (project "kria-k26-devboard"
        (path ""
          (reference "C186") (unit 1)
        )
      )
    )
  )

  (symbol (lib_id "kria-k26-devboard:C_10u_25V_0603") (at 29.845 94.615 270) (unit 1)
    (in_bom yes) (on_board yes) (dnp no) (fields_autoplaced)
    (property "Reference" "C184" (at 26.67 95.8913 90)
      (effects (font (size 1.524 1.524)) (justify right))
    )
    (property "Value" "C_10u_25V_0603" (at 26.035 94.615 0)
      (effects (font (size 1.524 1.524)) hide)
    )
    (property "Footprint" "kria-k26-devboard-footprints:C_0603_1608Metric" (at 34.925 99.695 0)
      (effects (font (size 1.27 1.27) (thickness 0.15)) (justify left bottom) hide)
    )
    (property "Datasheet" " " (at 29.845 94.615 0)
      (effects (font (size 1.27 1.27) (thickness 0.15)) (justify left bottom) hide)
    )
    (property "Manufacturer" "TDK" (at 40.005 99.695 0)
      (effects (font (size 1.27 1.27) (thickness 0.15)) (justify left bottom) hide)
    )
    (property "MPN" "C1608X5R1E106M080AC" (at 37.465 99.695 0)
      (effects (font (size 1.27 1.27) (thickness 0.15)) (justify left bottom) hide)
    )
    (property "Val" "10u/25V" (at 26.67 99.0662 90)
      (effects (font (size 1.27 1.27) (thickness 0.15)) (justify right))
    )
    (property "License" "Apache-2.0" (at 6.985 114.935 0)
      (effects (font (size 1.27 1.27) (thickness 0.15)) (justify left bottom) hide)
    )
    (property "Author" "Antmicro" (at 4.445 114.935 0)
      (effects (font (size 1.27 1.27) (thickness 0.15)) (justify left bottom) hide)
    )
    (property "Voltage" "" (at 1.905 114.935 0)
      (effects (font (size 1.27 1.27)) (justify left bottom) hide)
    )
    (property "Dielectric" "" (at -0.635 114.935 0)
      (effects (font (size 1.27 1.27)) (justify left bottom) hide)
    )
    (pin "1")
    (pin "2")
    (instances
      (project "kria-k26-devboard"
        (path ""
          (reference "C184") (unit 1)
        )
      )
    )
  )

  (symbol (lib_id "kria-k26-devboard:C_100n_0402") (at 75.565 97.155 0) (unit 1)
    (in_bom yes) (on_board yes) (dnp no)
    (property "Reference" "C192" (at 81.915 95.885 0)
      (effects (font (size 1.524 1.524)))
    )
    (property "Value" "C_100n_0402" (at 75.565 100.965 0)
      (effects (font (size 1.524 1.524)) hide)
    )
    (property "Footprint" "kria-k26-devboard-footprints:C_0402_1005Metric" (at 80.645 92.075 0)
      (effects (font (size 1.27 1.27) (thickness 0.15)) (justify left bottom) hide)
    )
    (property "Datasheet" "https://search.murata.co.jp/Ceramy/image/img/A01X/G101/ENG/GRM155R61H104KE14-01.pdf" (at 75.565 97.155 0)
      (effects (font (size 1.27 1.27) (thickness 0.15)) (justify left bottom) hide)
    )
    (property "Manufacturer" "Murata" (at 80.645 86.995 0)
      (effects (font (size 1.27 1.27) (thickness 0.15)) (justify left bottom) hide)
    )
    (property "MPN" "GRM155R61H104KE14D" (at 80.645 89.535 0)
      (effects (font (size 1.27 1.27) (thickness 0.15)) (justify left bottom) hide)
    )
    (property "Val" "100n" (at 81.28 98.425 0)
      (effects (font (size 1.27 1.27) (thickness 0.15)))
    )
    (property "License" "Apache-2.0" (at 95.885 120.015 0)
      (effects (font (size 1.27 1.27) (thickness 0.15)) (justify left bottom) hide)
    )
    (property "Author" "Antmicro" (at 95.885 122.555 0)
      (effects (font (size 1.27 1.27) (thickness 0.15)) (justify left bottom) hide)
    )
    (property "Voltage" "50V" (at 95.885 125.095 0)
      (effects (font (size 1.27 1.27)) (justify left bottom) hide)
    )
    (property "Dielectric" "X5R" (at 95.885 127.635 0)
      (effects (font (size 1.27 1.27)) (justify left bottom) hide)
    )
    (pin "1")
    (pin "2")
    (instances
      (project "kria-k26-devboard"
        (path ""
          (reference "C192") (unit 1)
        )
      )
    )
  )

  (symbol (lib_id "kria-k26-devboard:L_3u3_6.6A_XEL4030") (at 88.265 93.345 0) (unit 1)
    (in_bom yes) (on_board yes) (dnp no) (fields_autoplaced)
    (property "Reference" "L2" (at 90.805 87.63 0)
      (effects (font (size 1.27 1.27)))
    )
    (property "Value" "L_3u3_5.9A_XEL4030" (at 90.805 87.63 0)
      (effects (font (size 1.27 1.27)) hide)
    )
    (property "Footprint" "kria-k26-devboard-footprints:L_Coilcraft-XEL4030" (at 108.585 86.995 0)
      (effects (font (size 1.27 1.27) (thickness 0.15)) (justify left bottom) hide)
    )
    (property "Datasheet" "https://www.coilcraft.com/getmedia/8245f050-f190-4295-8c41-7c03d662ee3d/xel4030.pdf" (at 89.662 92.583 0)
      (effects (font (size 1.27 1.27) (thickness 0.15)) (justify left bottom) hide)
    )
    (property "MPN" "XEL4030-332MEC" (at 93.345 80.645 0)
      (effects (font (size 1.27 1.27) (thickness 0.15)) (justify left bottom) hide)
    )
    (property "Manufacturer" "Coilcraft" (at 95.885 78.105 0)
      (effects (font (size 1.27 1.27) (thickness 0.15)) (justify left bottom) hide)
    )
    (property "Val" "3u3/5.9A" (at 90.805 90.17 0)
      (effects (font (size 1.27 1.27) (thickness 0.15)))
    )
    (property "Size" "4x4" (at 91.44 85.09 0)
      (effects (font (size 1.27 1.27) (thickness 0.15)) (justify left bottom) hide)
    )
    (property "ISat" "" (at 102.235 109.855 0)
      (effects (font (size 1.27 1.27)) (justify left) hide)
    )
    (property "IMax" "" (at 102.235 113.665 0)
      (effects (font (size 1.27 1.27) (thickness 0.15)) (justify left bottom) hide)
    )
    (property "Author" "Antmicro" (at 102.235 118.745 0)
      (effects (font (size 1.27 1.27) (thickness 0.15)) (justify left bottom) hide)
    )
    (property "License" "Apache-2.0" (at 102.235 121.285 0)
      (effects (font (size 1.27 1.27) (thickness 0.15)) (justify left bottom) hide)
    )
    (pin "1")
    (pin "2")
    (instances
      (project "kria-k26-devboard"
        (path ""
          (reference "L2") (unit 1)
        )
      )
    )
  )

  (symbol (lib_id "kria-k26-devboard:R_24k_0402") (at 95.885 106.045 270) (unit 1)
    (in_bom yes) (on_board yes) (dnp no) (fields_autoplaced)
    (property "Reference" "R125" (at 97.663 107.315 90)
      (effects (font (size 1.524 1.524)) (justify left))
    )
    (property "Value" "R_24k_0402" (at 92.075 106.045 0)
      (effects (font (size 1.524 1.524)) hide)
    )
    (property "Footprint" "kria-k26-devboard-footprints:R_0402_1005Metric" (at 100.965 111.125 0)
      (effects (font (size 1.27 1.27) (thickness 0.15)) (justify left bottom) hide)
    )
    (property "Datasheet" "https://www.bourns.com/docs/product-datasheets/cr.pdf" (at 95.885 106.045 0)
      (effects (font (size 1.27 1.27) (thickness 0.15)) (justify left bottom) hide)
    )
    (property "Manufacturer" "Bourns" (at 106.045 111.125 0)
      (effects (font (size 1.27 1.27) (thickness 0.15)) (justify left bottom) hide)
    )
    (property "MPN" "CR0402-FX-2402GLF" (at 103.505 111.125 0)
      (effects (font (size 1.27 1.27) (thickness 0.15)) (justify left bottom) hide)
    )
    (property "Val" "24k" (at 97.663 110.4899 90)
      (effects (font (size 1.27 1.27) (thickness 0.15)) (justify left))
    )
    (property "License" "Apache-2.0" (at 70.485 126.365 0)
      (effects (font (size 1.27 1.27) (thickness 0.15)) (justify left bottom) hide)
    )
    (property "Author" "Antmicro" (at 67.945 126.365 0)
      (effects (font (size 1.27 1.27) (thickness 0.15)) (justify left bottom) hide)
    )
    (property "Tolerance" "1%" (at 85.725 126.365 0)
      (effects (font (size 1.27 1.27)) (justify left bottom) hide)
    )
    (pin "1")
    (pin "2")
    (instances
      (project "kria-k26-devboard"
        (path ""
          (reference "R125") (unit 1)
        )
      )
    )
  )

  (symbol (lib_id "kria-k26-devboard:C_22p_0402") (at 86.995 103.505 90) (unit 1)
    (in_bom yes) (on_board yes) (dnp no)
    (property "Reference" "C194" (at 93.345 99.06 90)
      (effects (font (size 1.524 1.524)) (justify left))
    )
    (property "Value" "C_22p_0402" (at 90.805 103.505 0)
      (effects (font (size 1.524 1.524)) hide)
    )
    (property "Footprint" "kria-k26-devboard-footprints:C_0402_1005Metric" (at 81.915 98.425 0)
      (effects (font (size 1.27 1.27) (thickness 0.15)) (justify left bottom) hide)
    )
    (property "Datasheet" " " (at 86.995 103.505 0)
      (effects (font (size 1.27 1.27) (thickness 0.15)) (justify left bottom) hide)
    )
    (property "Manufacturer" "Yaego" (at 76.835 98.425 0)
      (effects (font (size 1.27 1.27) (thickness 0.15)) (justify left bottom) hide)
    )
    (property "MPN" "CC0402JRNPO9BN220" (at 79.375 98.425 0)
      (effects (font (size 1.27 1.27) (thickness 0.15)) (justify left bottom) hide)
    )
    (property "Val" "22p" (at 91.44 102.87 90)
      (effects (font (size 1.27 1.27) (thickness 0.15)) (justify left))
    )
    (property "License" "Apache-2.0" (at 109.855 83.185 0)
      (effects (font (size 1.27 1.27) (thickness 0.15)) (justify left bottom) hide)
    )
    (property "Author" "Antmicro" (at 112.395 83.185 0)
      (effects (font (size 1.27 1.27) (thickness 0.15)) (justify left bottom) hide)
    )
    (property "Voltage" "" (at 114.935 83.185 0)
      (effects (font (size 1.27 1.27)) (justify left bottom) hide)
    )
    (property "Dielectric" "" (at 117.475 83.185 0)
      (effects (font (size 1.27 1.27)) (justify left bottom) hide)
    )
    (pin "1")
    (pin "2")
    (instances
      (project "kria-k26-devboard"
        (path ""
          (reference "C194") (unit 1)
        )
      )
    )
  )

  (symbol (lib_id "kria-k26-devboard:R_100k_0402") (at 50.8 93.345 180) (unit 1)
    (in_bom yes) (on_board yes) (dnp no)
    (property "Reference" "R119" (at 53.34 92.075 0)
      (effects (font (size 1.524 1.524)))
    )
    (property "Value" "R_100k_0402" (at 50.8 89.535 0)
      (effects (font (size 1.524 1.524)) hide)
    )
    (property "Footprint" "kria-k26-devboard-footprints:R_0402_1005Metric" (at 45.72 98.425 0)
      (effects (font (size 1.27 1.27) (thickness 0.15)) (justify left bottom) hide)
    )
    (property "Datasheet" "https://www.bourns.com/docs/product-datasheets/cr.pdf" (at 50.8 93.345 0)
      (effects (font (size 1.27 1.27) (thickness 0.15)) (justify left bottom) hide)
    )
    (property "Manufacturer" "Bourns" (at 45.72 103.505 0)
      (effects (font (size 1.27 1.27) (thickness 0.15)) (justify left bottom) hide)
    )
    (property "MPN" "CR0402-FX-1003GLF" (at 45.72 100.965 0)
      (effects (font (size 1.27 1.27) (thickness 0.15)) (justify left bottom) hide)
    )
    (property "Val" "100k" (at 53.34 94.615 0)
      (effects (font (size 1.27 1.27) (thickness 0.15)))
    )
    (property "License" "Apache-2.0" (at 30.48 67.945 0)
      (effects (font (size 1.27 1.27) (thickness 0.15)) (justify left bottom) hide)
    )
    (property "Author" "Antmicro" (at 30.48 65.405 0)
      (effects (font (size 1.27 1.27) (thickness 0.15)) (justify left bottom) hide)
    )
    (property "Tolerance" "1%" (at 30.48 83.185 0)
      (effects (font (size 1.27 1.27)) (justify left bottom) hide)
    )
    (pin "1")
    (pin "2")
    (instances
      (project "kria-k26-devboard"
        (path ""
          (reference "R119") (unit 1)
        )
      )
    )
  )

  (symbol (lib_id "kria-k26-devboard:GND") (at 55.245 57.15 0) (unit 1)
    (in_bom yes) (on_board yes) (dnp no) (fields_autoplaced)
    (property "Reference" "#PWR0403" (at 55.245 63.5 0)
      (effects (font (size 1.27 1.27)) hide)
    )
    (property "Value" "GND" (at 55.245 62.23 0)
      (effects (font (size 1.27 1.27)))
    )
    (property "Footprint" "" (at 64.135 64.77 0)
      (effects (font (size 1.27 1.27) (thickness 0.15)) (justify left bottom) hide)
    )
    (property "Datasheet" "" (at 64.135 69.85 0)
      (effects (font (size 1.27 1.27) (thickness 0.15)) (justify left bottom) hide)
    )
    (property "Author" "Antmicro" (at 64.135 64.77 0)
      (effects (font (size 1.27 1.27) (thickness 0.15)) (justify left bottom) hide)
    )
    (property "License" "Apache-2.0" (at 64.135 67.31 0)
      (effects (font (size 1.27 1.27) (thickness 0.15)) (justify left bottom) hide)
    )
    (pin "1")
    (instances
      (project "kria-k26-devboard"
        (path ""
          (reference "#PWR0403") (unit 1)
        )
      )
    )
  )

  (symbol (lib_id "kria-k26-devboard:TP_0.75mm_SMD") (at 118.745 36.83 90) (unit 1)
    (in_bom yes) (on_board yes) (dnp no) (fields_autoplaced)
    (property "Reference" "TP51" (at 121.285 33.6549 90)
      (effects (font (size 1.27 1.27)) (justify right))
    )
    (property "Value" "TP_0.75mm_SMD" (at 121.285 36.83 0)
      (effects (font (size 1.27 1.27) (thickness 0.15)) (justify left bottom) hide)
    )
    (property "Footprint" "kria-k26-devboard-footprints:TP_SMD_0.75mm" (at 113.665 31.75 0)
      (effects (font (size 1.27 1.27) (thickness 0.15)) (justify left bottom) hide)
    )
    (property "Datasheet" "" (at 111.125 31.75 0)
      (effects (font (size 1.27 1.27) (thickness 0.15)) (justify left bottom) hide)
    )
    (property "MPN" "" (at 118.745 36.83 0)
      (effects (font (size 1.27 1.27) (thickness 0.15)) (justify left bottom) hide)
    )
    (property "Manufacturer" "" (at 118.745 36.83 0)
      (effects (font (size 1.27 1.27) (thickness 0.15)) (justify left bottom) hide)
    )
    (property "Author" "Antmicro" (at 133.985 21.59 0)
      (effects (font (size 1.27 1.27) (thickness 0.15)) (justify left bottom) hide)
    )
    (property "License" "Apache-2.0" (at 136.525 21.59 0)
      (effects (font (size 1.27 1.27) (thickness 0.15)) (justify left bottom) hide)
    )
    (pin "1")
    (instances
      (project "kria-k26-devboard"
        (path ""
          (reference "TP51") (unit 1)
        )
      )
    )
  )

  (symbol (lib_id "kria-k26-devboard:TP_0.75mm_SMD") (at 118.11 92.075 90) (unit 1)
    (in_bom yes) (on_board yes) (dnp no) (fields_autoplaced)
    (property "Reference" "TP50" (at 120.015 88.8999 90)
      (effects (font (size 1.27 1.27)) (justify right))
    )
    (property "Value" "TP_0.75mm_SMD" (at 120.65 92.075 0)
      (effects (font (size 1.27 1.27) (thickness 0.15)) (justify left bottom) hide)
    )
    (property "Footprint" "kria-k26-devboard-footprints:TP_SMD_0.75mm" (at 113.03 86.995 0)
      (effects (font (size 1.27 1.27) (thickness 0.15)) (justify left bottom) hide)
    )
    (property "Datasheet" "" (at 110.49 86.995 0)
      (effects (font (size 1.27 1.27) (thickness 0.15)) (justify left bottom) hide)
    )
    (property "MPN" "" (at 118.11 92.075 0)
      (effects (font (size 1.27 1.27) (thickness 0.15)) (justify left bottom) hide)
    )
    (property "Manufacturer" "" (at 118.11 92.075 0)
      (effects (font (size 1.27 1.27) (thickness 0.15)) (justify left bottom) hide)
    )
    (property "Author" "Antmicro" (at 133.35 76.835 0)
      (effects (font (size 1.27 1.27) (thickness 0.15)) (justify left bottom) hide)
    )
    (property "License" "Apache-2.0" (at 135.89 76.835 0)
      (effects (font (size 1.27 1.27) (thickness 0.15)) (justify left bottom) hide)
    )
    (pin "1")
    (instances
      (project "kria-k26-devboard"
        (path ""
          (reference "TP50") (unit 1)
        )
      )
    )
  )

  (symbol (lib_id "kria-k26-devboard:L_1u_2.6A_0806") (at 230.505 152.4 0) (unit 1)
    (in_bom yes) (on_board yes) (dnp no)
    (property "Reference" "L6" (at 233.045 147.955 0)
      (effects (font (size 1.524 1.524)))
    )
    (property "Value" "L_1u_2.6A_0806" (at 233.045 146.05 0)
      (effects (font (size 1.524 1.524)) hide)
    )
    (property "Footprint" "kria-k26-devboard-footprints:L_0806_2016Metric" (at 251.46 143.51 0)
      (effects (font (size 1.27 1.27) (thickness 0.15)) (justify left bottom) hide)
    )
    (property "Datasheet" "https://www.bourns.com/docs/Product-Datasheets/SRP2010.pdf" (at 231.902 151.638 0)
      (effects (font (size 1.27 1.27) (thickness 0.15)) (justify left bottom) hide)
    )
    (property "Manufacturer" "Bourns" (at 234.315 133.35 0)
      (effects (font (size 1.27 1.27) (thickness 0.15)) (justify left bottom) hide)
    )
    (property "MPN" "SRP2010-1R0M" (at 238.125 135.89 0)
      (effects (font (size 1.27 1.27) (thickness 0.15)) (justify left bottom) hide)
    )
    (property "Size" "2.0x1.6" (at 233.68 140.97 0)
      (effects (font (size 1.27 1.27) (thickness 0.15)) (justify left bottom) hide)
    )
    (property "Val" "1u/2.6A" (at 233.045 149.86 0)
      (effects (font (size 1.27 1.27) (thickness 0.15)))
    )
    (property "ISat" "" (at 244.475 168.91 0)
      (effects (font (size 1.27 1.27)) (justify left) hide)
    )
    (property "IMax" "" (at 244.475 172.72 0)
      (effects (font (size 1.27 1.27) (thickness 0.15)) (justify left bottom) hide)
    )
    (property "Author" "Antmicro" (at 244.475 177.8 0)
      (effects (font (size 1.27 1.27) (thickness 0.15)) (justify left bottom) hide)
    )
    (property "License" "Apache-2.0" (at 244.475 180.34 0)
      (effects (font (size 1.27 1.27) (thickness 0.15)) (justify left bottom) hide)
    )
    (pin "1")
    (pin "2")
    (instances
      (project "kria-k26-devboard"
        (path ""
          (reference "L6") (unit 1)
        )
      )
    )
  )

  (symbol (lib_id "kria-k26-devboard:LED_G_0603_LG_L29K-G2J1-24-Z") (at 195.58 245.11 270) (unit 1)
    (in_bom yes) (on_board yes) (dnp no) (fields_autoplaced)
    (property "Reference" "D17" (at 199.39 247.65 90)
      (effects (font (size 1.524 1.524)) (justify left))
    )
    (property "Value" "LED_G_0603_LG_L29K-G2J1-24-Z" (at 199.39 250.8249 90)
      (effects (font (size 1.27 1.27) (thickness 0.15)) (justify left) hide)
    )
    (property "Footprint" "kria-k26-devboard-footprints:LED_0603_1608Metric_G" (at 200.66 250.19 0)
      (effects (font (size 1.27 1.27) (thickness 0.15)) (justify left bottom) hide)
    )
    (property "Datasheet" "https://dammedia.osram.info/media/resource/hires/osram-dam-2493945/LG%20L29K.pdf" (at 203.2 250.19 0)
      (effects (font (size 1.27 1.27) (thickness 0.15)) (justify left bottom) hide)
    )
    (property "MPN" "LG L29K-G2J1-24-Z" (at 199.39 250.8249 90)
      (effects (font (size 1.27 1.27) (thickness 0.15)) (justify left) hide)
    )
    (property "Manufacturer" "OSRAM" (at 223.52 250.19 0)
      (effects (font (size 1.27 1.27) (thickness 0.15)) (justify left bottom) hide)
    )
    (property "Author" "Antmicro" (at 175.26 267.97 0)
      (effects (font (size 1.27 1.27) (thickness 0.15)) (justify left bottom) hide)
    )
    (property "License" "Apache-2.0" (at 172.72 267.97 0)
      (effects (font (size 1.27 1.27) (thickness 0.15)) (justify left bottom) hide)
    )
    (property "Color" "Green" (at 199.39 250.19 90)
      (effects (font (size 1.27 1.27)) (justify left))
    )
    (pin "1")
    (pin "2")
    (instances
      (project "kria-k26-devboard"
        (path ""
          (reference "D17") (unit 1)
        )
      )
    )
  )

  (symbol (lib_id "kria-k26-devboard:LED_G_0603_LG_L29K-G2J1-24-Z") (at 233.68 245.11 270) (unit 1)
    (in_bom yes) (on_board yes) (dnp no) (fields_autoplaced)
    (property "Reference" "D18" (at 237.49 247.65 90)
      (effects (font (size 1.524 1.524)) (justify left))
    )
    (property "Value" "LED_G_0603_LG_L29K-G2J1-24-Z" (at 237.49 250.8249 90)
      (effects (font (size 1.27 1.27) (thickness 0.15)) (justify left) hide)
    )
    (property "Footprint" "kria-k26-devboard-footprints:LED_0603_1608Metric_G" (at 238.76 250.19 0)
      (effects (font (size 1.27 1.27) (thickness 0.15)) (justify left bottom) hide)
    )
    (property "Datasheet" "https://dammedia.osram.info/media/resource/hires/osram-dam-2493945/LG%20L29K.pdf" (at 241.3 250.19 0)
      (effects (font (size 1.27 1.27) (thickness 0.15)) (justify left bottom) hide)
    )
    (property "MPN" "LG L29K-G2J1-24-Z" (at 237.49 250.8249 90)
      (effects (font (size 1.27 1.27) (thickness 0.15)) (justify left) hide)
    )
    (property "Manufacturer" "OSRAM" (at 261.62 250.19 0)
      (effects (font (size 1.27 1.27) (thickness 0.15)) (justify left bottom) hide)
    )
    (property "Author" "Antmicro" (at 213.36 267.97 0)
      (effects (font (size 1.27 1.27) (thickness 0.15)) (justify left bottom) hide)
    )
    (property "License" "Apache-2.0" (at 210.82 267.97 0)
      (effects (font (size 1.27 1.27) (thickness 0.15)) (justify left bottom) hide)
    )
    (property "Color" "Green" (at 237.49 250.19 90)
      (effects (font (size 1.27 1.27)) (justify left))
    )
    (pin "1")
    (pin "2")
    (instances
      (project "kria-k26-devboard"
        (path ""
          (reference "D18") (unit 1)
        )
      )
    )
  )

  (symbol (lib_id "kria-k26-devboard:LED_G_0603_LG_L29K-G2J1-24-Z") (at 274.955 245.11 270) (unit 1)
    (in_bom yes) (on_board yes) (dnp no) (fields_autoplaced)
    (property "Reference" "D20" (at 278.13 247.65 90)
      (effects (font (size 1.524 1.524)) (justify left))
    )
    (property "Value" "LED_G_0603_LG_L29K-G2J1-24-Z" (at 278.765 250.8249 90)
      (effects (font (size 1.27 1.27) (thickness 0.15)) (justify left) hide)
    )
    (property "Footprint" "kria-k26-devboard-footprints:LED_0603_1608Metric_G" (at 280.035 250.19 0)
      (effects (font (size 1.27 1.27) (thickness 0.15)) (justify left bottom) hide)
    )
    (property "Datasheet" "https://dammedia.osram.info/media/resource/hires/osram-dam-2493945/LG%20L29K.pdf" (at 282.575 250.19 0)
      (effects (font (size 1.27 1.27) (thickness 0.15)) (justify left bottom) hide)
    )
    (property "MPN" "LG L29K-G2J1-24-Z" (at 278.765 250.8249 90)
      (effects (font (size 1.27 1.27) (thickness 0.15)) (justify left) hide)
    )
    (property "Manufacturer" "OSRAM" (at 302.895 250.19 0)
      (effects (font (size 1.27 1.27) (thickness 0.15)) (justify left bottom) hide)
    )
    (property "Author" "Antmicro" (at 254.635 267.97 0)
      (effects (font (size 1.27 1.27) (thickness 0.15)) (justify left bottom) hide)
    )
    (property "License" "Apache-2.0" (at 252.095 267.97 0)
      (effects (font (size 1.27 1.27) (thickness 0.15)) (justify left bottom) hide)
    )
    (property "Color" "Green" (at 278.13 250.19 90)
      (effects (font (size 1.27 1.27)) (justify left))
    )
    (pin "1")
    (pin "2")
    (instances
      (project "kria-k26-devboard"
        (path ""
          (reference "D20") (unit 1)
        )
      )
    )
  )

  (symbol (lib_id "kria-k26-devboard:DTC014T_SOT-416") (at 187.96 259.715 0) (unit 1)
    (in_bom yes) (on_board yes) (dnp no) (fields_autoplaced)
    (property "Reference" "Q13" (at 198.12 258.4449 0)
      (effects (font (size 1.27 1.27)) (justify left))
    )
    (property "Value" "DTC014T_SOT-416" (at 198.12 260.9849 0)
      (effects (font (size 1.27 1.27) (thickness 0.15)) (justify left) hide)
    )
    (property "Footprint" "kria-k26-devboard-footprints:SOT-416" (at 193.04 267.335 0)
      (effects (font (size 1.27 1.27) (thickness 0.15)) (justify left bottom) hide)
    )
    (property "Datasheet" "https://www.rohm.com/datasheet?p=DTC014TEB&dist=Mouser&media=referral&source=mouser.com&campaign=Mouser" (at 187.96 259.715 0)
      (effects (font (size 1.27 1.27) (thickness 0.15)) (justify left bottom) hide)
    )
    (property "Manufacturer" "ROHM Semiconductor" (at 203.2 262.255 0)
      (effects (font (size 1.27 1.27) (thickness 0.15)) (justify left bottom) hide)
    )
    (property "MPN" "DTC014TEBTL" (at 198.12 260.9849 0)
      (effects (font (size 1.27 1.27) (thickness 0.15)) (justify left))
    )
    (property "Author" "Antmicro" (at 213.36 280.035 0)
      (effects (font (size 1.27 1.27) (thickness 0.15)) (justify left bottom) hide)
    )
    (property "License" "Apache-2.0" (at 213.36 282.575 0)
      (effects (font (size 1.27 1.27) (thickness 0.15)) (justify left bottom) hide)
    )
    (pin "1")
    (pin "2")
    (pin "3")
    (instances
      (project "kria-k26-devboard"
        (path ""
          (reference "Q13") (unit 1)
        )
      )
    )
  )

  (symbol (lib_id "kria-k26-devboard:DTC014T_SOT-416") (at 226.06 259.715 0) (unit 1)
    (in_bom yes) (on_board yes) (dnp no) (fields_autoplaced)
    (property "Reference" "Q14" (at 236.22 258.4449 0)
      (effects (font (size 1.27 1.27)) (justify left))
    )
    (property "Value" "DTC014T_SOT-416" (at 236.22 260.9849 0)
      (effects (font (size 1.27 1.27) (thickness 0.15)) (justify left) hide)
    )
    (property "Footprint" "kria-k26-devboard-footprints:SOT-416" (at 231.14 267.335 0)
      (effects (font (size 1.27 1.27) (thickness 0.15)) (justify left bottom) hide)
    )
    (property "Datasheet" "https://www.rohm.com/datasheet?p=DTC014TEB&dist=Mouser&media=referral&source=mouser.com&campaign=Mouser" (at 226.06 259.715 0)
      (effects (font (size 1.27 1.27) (thickness 0.15)) (justify left bottom) hide)
    )
    (property "Manufacturer" "ROHM Semiconductor" (at 241.3 262.255 0)
      (effects (font (size 1.27 1.27) (thickness 0.15)) (justify left bottom) hide)
    )
    (property "MPN" "DTC014TEBTL" (at 236.22 260.9849 0)
      (effects (font (size 1.27 1.27) (thickness 0.15)) (justify left))
    )
    (property "Author" "Antmicro" (at 251.46 280.035 0)
      (effects (font (size 1.27 1.27) (thickness 0.15)) (justify left bottom) hide)
    )
    (property "License" "Apache-2.0" (at 251.46 282.575 0)
      (effects (font (size 1.27 1.27) (thickness 0.15)) (justify left bottom) hide)
    )
    (pin "1")
    (pin "2")
    (pin "3")
    (instances
      (project "kria-k26-devboard"
        (path ""
          (reference "Q14") (unit 1)
        )
      )
    )
  )

  (symbol (lib_id "kria-k26-devboard:DTC014T_SOT-416") (at 267.335 259.715 0) (unit 1)
    (in_bom yes) (on_board yes) (dnp no) (fields_autoplaced)
    (property "Reference" "Q15" (at 277.495 258.4449 0)
      (effects (font (size 1.27 1.27)) (justify left))
    )
    (property "Value" "DTC014T_SOT-416" (at 277.495 260.9849 0)
      (effects (font (size 1.27 1.27) (thickness 0.15)) (justify left) hide)
    )
    (property "Footprint" "kria-k26-devboard-footprints:SOT-416" (at 272.415 267.335 0)
      (effects (font (size 1.27 1.27) (thickness 0.15)) (justify left bottom) hide)
    )
    (property "Datasheet" "https://www.rohm.com/datasheet?p=DTC014TEB&dist=Mouser&media=referral&source=mouser.com&campaign=Mouser" (at 267.335 259.715 0)
      (effects (font (size 1.27 1.27) (thickness 0.15)) (justify left bottom) hide)
    )
    (property "Manufacturer" "ROHM Semiconductor" (at 282.575 262.255 0)
      (effects (font (size 1.27 1.27) (thickness 0.15)) (justify left bottom) hide)
    )
    (property "MPN" "DTC014TEBTL" (at 277.495 260.9849 0)
      (effects (font (size 1.27 1.27) (thickness 0.15)) (justify left))
    )
    (property "Author" "Antmicro" (at 292.735 280.035 0)
      (effects (font (size 1.27 1.27) (thickness 0.15)) (justify left bottom) hide)
    )
    (property "License" "Apache-2.0" (at 292.735 282.575 0)
      (effects (font (size 1.27 1.27) (thickness 0.15)) (justify left bottom) hide)
    )
    (pin "1")
    (pin "2")
    (pin "3")
    (instances
      (project "kria-k26-devboard"
        (path ""
          (reference "Q15") (unit 1)
        )
      )
    )
  )

  (symbol (lib_id "kria-k26-devboard:GND") (at 238.125 210.82 0) (unit 1)
    (in_bom yes) (on_board yes) (dnp no) (fields_autoplaced)
    (property "Reference" "#PWR0159" (at 238.125 217.17 0)
      (effects (font (size 1.27 1.27)) hide)
    )
    (property "Value" "GND" (at 238.125 215.9 0)
      (effects (font (size 1.27 1.27)))
    )
    (property "Footprint" "" (at 247.015 218.44 0)
      (effects (font (size 1.27 1.27) (thickness 0.15)) (justify left bottom) hide)
    )
    (property "Datasheet" "" (at 247.015 223.52 0)
      (effects (font (size 1.27 1.27) (thickness 0.15)) (justify left bottom) hide)
    )
    (property "Author" "Antmicro" (at 247.015 218.44 0)
      (effects (font (size 1.27 1.27) (thickness 0.15)) (justify left bottom) hide)
    )
    (property "License" "Apache-2.0" (at 247.015 220.98 0)
      (effects (font (size 1.27 1.27) (thickness 0.15)) (justify left bottom) hide)
    )
    (pin "1")
    (instances
      (project "kria-k26-devboard"
        (path ""
          (reference "#PWR0159") (unit 1)
        )
      )
    )
  )

  (symbol (lib_id "kria-k26-devboard:R_0R_22.4A_0603") (at 260.985 152.4 0) (unit 1)
    (in_bom yes) (on_board yes) (dnp no)
    (property "Reference" "R156" (at 263.525 148.59 0)
      (effects (font (size 1.524 1.524)))
    )
    (property "Value" "R_0R_22.4A_0603" (at 260.985 156.21 0)
      (effects (font (size 1.27 1.27) (thickness 0.15)) (justify left bottom) hide)
    )
    (property "Footprint" "kria-k26-devboard-footprints:R_0603_1608Metric" (at 266.065 147.32 0)
      (effects (font (size 1.27 1.27) (thickness 0.15)) (justify left bottom) hide)
    )
    (property "Datasheet" "https://fscdn.rohm.com/en/products/databook/datasheet/passive/resistor/chip_resistor/pmr-jpw-e.pdf" (at 260.985 152.4 0)
      (effects (font (size 1.27 1.27) (thickness 0.15)) (justify left bottom) hide)
    )
    (property "Manufacturer" "ROHM Semiconductor" (at 266.065 142.24 0)
      (effects (font (size 1.27 1.27) (thickness 0.15)) (justify left bottom) hide)
    )
    (property "MPN" "PMR03EZPJ000" (at 266.065 144.78 0)
      (effects (font (size 1.27 1.27) (thickness 0.15)) (justify left bottom) hide)
    )
    (property "Val" "0R" (at 263.525 150.495 0)
      (effects (font (size 1.27 1.27) (thickness 0.15)))
    )
    (property "Author" "Antmicro" (at 283.845 175.26 0)
      (effects (font (size 1.27 1.27) (thickness 0.15)) (justify left bottom) hide)
    )
    (property "License" "Apache-2.0" (at 283.845 177.8 0)
      (effects (font (size 1.27 1.27) (thickness 0.15)) (justify left bottom) hide)
    )
    (property "Max. Curr." "22.4A" (at 263.525 154.305 0)
      (effects (font (size 1.27 1.27) (thickness 0.15)))
    )
    (pin "1")
    (pin "2")
    (instances
      (project "kria-k26-devboard"
        (path ""
          (reference "R156") (unit 1)
        )
      )
    )
  )

  (symbol (lib_id "kria-k26-devboard:C_22u_16V_0603") (at 117.475 50.8 270) (unit 1)
    (in_bom yes) (on_board yes) (dnp no)
    (property "Reference" "C197" (at 118.745 51.435 90)
      (effects (font (size 1.524 1.524)) (justify left))
    )
    (property "Value" "C_22u_16V_0603" (at 113.665 50.8 0)
      (effects (font (size 1.524 1.524)) hide)
    )
    (property "Footprint" "kria-k26-devboard-footprints:C_0603_1608Metric" (at 122.555 55.88 0)
      (effects (font (size 1.27 1.27) (thickness 0.15)) (justify left bottom) hide)
    )
    (property "Datasheet" "https://www.mouser.pl/datasheet/2/585/MLCC-1837944.pdf" (at 117.475 50.8 0)
      (effects (font (size 1.27 1.27) (thickness 0.15)) (justify left bottom) hide)
    )
    (property "Manufacturer" "Samsung" (at 127.635 55.88 0)
      (effects (font (size 1.27 1.27) (thickness 0.15)) (justify left bottom) hide)
    )
    (property "MPN" "CL10A226MO7JZNC" (at 125.095 55.88 0)
      (effects (font (size 1.27 1.27) (thickness 0.15)) (justify left bottom) hide)
    )
    (property "Val" "22u/16V" (at 118.11 55.245 90)
      (effects (font (size 1.27 1.27) (thickness 0.15)) (justify left))
    )
    (property "License" "Apache-2.0" (at 94.615 71.12 0)
      (effects (font (size 1.27 1.27) (thickness 0.15)) (justify left bottom) hide)
    )
    (property "Author" "Antmicro" (at 92.075 71.12 0)
      (effects (font (size 1.27 1.27) (thickness 0.15)) (justify left bottom) hide)
    )
    (property "Voltage" "" (at 89.535 71.12 0)
      (effects (font (size 1.27 1.27)) (justify left bottom) hide)
    )
    (property "Dielectric" "" (at 86.995 71.12 0)
      (effects (font (size 1.27 1.27)) (justify left bottom) hide)
    )
    (pin "1")
    (pin "2")
    (instances
      (project "kria-k26-devboard"
        (path ""
          (reference "C197") (unit 1)
        )
      )
    )
  )

  (symbol (lib_id "kria-k26-devboard:GND") (at 258.445 170.18 0) (unit 1)
    (in_bom yes) (on_board yes) (dnp no) (fields_autoplaced)
    (property "Reference" "#PWR0168" (at 258.445 176.53 0)
      (effects (font (size 1.27 1.27)) hide)
    )
    (property "Value" "GND" (at 258.445 175.26 0)
      (effects (font (size 1.27 1.27)))
    )
    (property "Footprint" "" (at 267.335 177.8 0)
      (effects (font (size 1.27 1.27) (thickness 0.15)) (justify left bottom) hide)
    )
    (property "Datasheet" "" (at 267.335 182.88 0)
      (effects (font (size 1.27 1.27) (thickness 0.15)) (justify left bottom) hide)
    )
    (property "Author" "Antmicro" (at 267.335 177.8 0)
      (effects (font (size 1.27 1.27) (thickness 0.15)) (justify left bottom) hide)
    )
    (property "License" "Apache-2.0" (at 267.335 180.34 0)
      (effects (font (size 1.27 1.27) (thickness 0.15)) (justify left bottom) hide)
    )
    (pin "1")
    (instances
      (project "kria-k26-devboard"
        (path ""
          (reference "#PWR0168") (unit 1)
        )
      )
    )
  )

  (symbol (lib_id "kria-k26-devboard:GND") (at 236.855 170.18 0) (unit 1)
    (in_bom yes) (on_board yes) (dnp no) (fields_autoplaced)
    (property "Reference" "#PWR0162" (at 236.855 176.53 0)
      (effects (font (size 1.27 1.27)) hide)
    )
    (property "Value" "GND" (at 236.855 175.26 0)
      (effects (font (size 1.27 1.27)))
    )
    (property "Footprint" "" (at 245.745 177.8 0)
      (effects (font (size 1.27 1.27) (thickness 0.15)) (justify left bottom) hide)
    )
    (property "Datasheet" "" (at 245.745 182.88 0)
      (effects (font (size 1.27 1.27) (thickness 0.15)) (justify left bottom) hide)
    )
    (property "Author" "Antmicro" (at 245.745 177.8 0)
      (effects (font (size 1.27 1.27) (thickness 0.15)) (justify left bottom) hide)
    )
    (property "License" "Apache-2.0" (at 245.745 180.34 0)
      (effects (font (size 1.27 1.27) (thickness 0.15)) (justify left bottom) hide)
    )
    (pin "1")
    (instances
      (project "kria-k26-devboard"
        (path ""
          (reference "#PWR0162") (unit 1)
        )
      )
    )
  )

  (symbol (lib_id "kria-k26-devboard:C_22u_16V_0603") (at 116.205 106.045 270) (unit 1)
    (in_bom yes) (on_board yes) (dnp no)
    (property "Reference" "C198" (at 116.84 106.68 90)
      (effects (font (size 1.524 1.524)) (justify left))
    )
    (property "Value" "C_22u_16V_0603" (at 112.395 106.045 0)
      (effects (font (size 1.524 1.524)) hide)
    )
    (property "Footprint" "kria-k26-devboard-footprints:C_0603_1608Metric" (at 121.285 111.125 0)
      (effects (font (size 1.27 1.27) (thickness 0.15)) (justify left bottom) hide)
    )
    (property "Datasheet" "https://www.mouser.pl/datasheet/2/585/MLCC-1837944.pdf" (at 116.205 106.045 0)
      (effects (font (size 1.27 1.27) (thickness 0.15)) (justify left bottom) hide)
    )
    (property "Manufacturer" "Samsung" (at 126.365 111.125 0)
      (effects (font (size 1.27 1.27) (thickness 0.15)) (justify left bottom) hide)
    )
    (property "MPN" "CL10A226MO7JZNC" (at 123.825 111.125 0)
      (effects (font (size 1.27 1.27) (thickness 0.15)) (justify left bottom) hide)
    )
    (property "Val" "22u/16V" (at 116.84 110.49 90)
      (effects (font (size 1.27 1.27) (thickness 0.15)) (justify left))
    )
    (property "License" "Apache-2.0" (at 93.345 126.365 0)
      (effects (font (size 1.27 1.27) (thickness 0.15)) (justify left bottom) hide)
    )
    (property "Author" "Antmicro" (at 90.805 126.365 0)
      (effects (font (size 1.27 1.27) (thickness 0.15)) (justify left bottom) hide)
    )
    (property "Voltage" "" (at 88.265 126.365 0)
      (effects (font (size 1.27 1.27)) (justify left bottom) hide)
    )
    (property "Dielectric" "" (at 85.725 126.365 0)
      (effects (font (size 1.27 1.27)) (justify left bottom) hide)
    )
    (pin "1")
    (pin "2")
    (instances
      (project "kria-k26-devboard"
        (path ""
          (reference "C198") (unit 1)
        )
      )
    )
  )

  (symbol (lib_id "kria-k26-devboard:GND") (at 247.65 130.175 0) (unit 1)
    (in_bom yes) (on_board yes) (dnp no) (fields_autoplaced)
    (property "Reference" "#PWR0158" (at 247.65 136.525 0)
      (effects (font (size 1.27 1.27)) hide)
    )
    (property "Value" "GND" (at 247.65 135.255 0)
      (effects (font (size 1.27 1.27)))
    )
    (property "Footprint" "" (at 256.54 137.795 0)
      (effects (font (size 1.27 1.27) (thickness 0.15)) (justify left bottom) hide)
    )
    (property "Datasheet" "" (at 256.54 142.875 0)
      (effects (font (size 1.27 1.27) (thickness 0.15)) (justify left bottom) hide)
    )
    (property "Author" "Antmicro" (at 256.54 137.795 0)
      (effects (font (size 1.27 1.27) (thickness 0.15)) (justify left bottom) hide)
    )
    (property "License" "Apache-2.0" (at 256.54 140.335 0)
      (effects (font (size 1.27 1.27) (thickness 0.15)) (justify left bottom) hide)
    )
    (pin "1")
    (instances
      (project "kria-k26-devboard"
        (path ""
          (reference "#PWR0158") (unit 1)
        )
      )
    )
  )

  (symbol (lib_id "kria-k26-devboard:GND") (at 196.85 124.46 0) (unit 1)
    (in_bom yes) (on_board yes) (dnp no) (fields_autoplaced)
    (property "Reference" "#PWR0155" (at 196.85 130.81 0)
      (effects (font (size 1.27 1.27)) hide)
    )
    (property "Value" "GND" (at 196.85 129.54 0)
      (effects (font (size 1.27 1.27)))
    )
    (property "Footprint" "" (at 205.74 132.08 0)
      (effects (font (size 1.27 1.27) (thickness 0.15)) (justify left bottom) hide)
    )
    (property "Datasheet" "" (at 205.74 137.16 0)
      (effects (font (size 1.27 1.27) (thickness 0.15)) (justify left bottom) hide)
    )
    (property "Author" "Antmicro" (at 205.74 132.08 0)
      (effects (font (size 1.27 1.27) (thickness 0.15)) (justify left bottom) hide)
    )
    (property "License" "Apache-2.0" (at 205.74 134.62 0)
      (effects (font (size 1.27 1.27) (thickness 0.15)) (justify left bottom) hide)
    )
    (pin "1")
    (instances
      (project "kria-k26-devboard"
        (path ""
          (reference "#PWR0155") (unit 1)
        )
      )
    )
  )

  (symbol (lib_id "kria-k26-devboard:C_22u_16V_0603") (at 125.73 106.045 270) (unit 1)
    (in_bom yes) (on_board yes) (dnp no)
    (property "Reference" "C200" (at 126.365 106.68 90)
      (effects (font (size 1.524 1.524)) (justify left))
    )
    (property "Value" "C_22u_16V_0603" (at 121.92 106.045 0)
      (effects (font (size 1.524 1.524)) hide)
    )
    (property "Footprint" "kria-k26-devboard-footprints:C_0603_1608Metric" (at 130.81 111.125 0)
      (effects (font (size 1.27 1.27) (thickness 0.15)) (justify left bottom) hide)
    )
    (property "Datasheet" "https://www.mouser.pl/datasheet/2/585/MLCC-1837944.pdf" (at 125.73 106.045 0)
      (effects (font (size 1.27 1.27) (thickness 0.15)) (justify left bottom) hide)
    )
    (property "Manufacturer" "Samsung" (at 135.89 111.125 0)
      (effects (font (size 1.27 1.27) (thickness 0.15)) (justify left bottom) hide)
    )
    (property "MPN" "CL10A226MO7JZNC" (at 133.35 111.125 0)
      (effects (font (size 1.27 1.27) (thickness 0.15)) (justify left bottom) hide)
    )
    (property "Val" "22u/16V" (at 126.365 110.49 90)
      (effects (font (size 1.27 1.27) (thickness 0.15)) (justify left))
    )
    (property "License" "Apache-2.0" (at 102.87 126.365 0)
      (effects (font (size 1.27 1.27) (thickness 0.15)) (justify left bottom) hide)
    )
    (property "Author" "Antmicro" (at 100.33 126.365 0)
      (effects (font (size 1.27 1.27) (thickness 0.15)) (justify left bottom) hide)
    )
    (property "Voltage" "" (at 97.79 126.365 0)
      (effects (font (size 1.27 1.27)) (justify left bottom) hide)
    )
    (property "Dielectric" "" (at 95.25 126.365 0)
      (effects (font (size 1.27 1.27)) (justify left bottom) hide)
    )
    (pin "1")
    (pin "2")
    (instances
      (project "kria-k26-devboard"
        (path ""
          (reference "C200") (unit 1)
        )
      )
    )
  )

  (symbol (lib_id "kria-k26-devboard:GND") (at 258.445 50.8 0) (unit 1)
    (in_bom yes) (on_board yes) (dnp no) (fields_autoplaced)
    (property "Reference" "#PWR0142" (at 258.445 57.15 0)
      (effects (font (size 1.27 1.27)) hide)
    )
    (property "Value" "GND" (at 258.445 55.88 0)
      (effects (font (size 1.27 1.27)))
    )
    (property "Footprint" "" (at 267.335 58.42 0)
      (effects (font (size 1.27 1.27) (thickness 0.15)) (justify left bottom) hide)
    )
    (property "Datasheet" "" (at 267.335 63.5 0)
      (effects (font (size 1.27 1.27) (thickness 0.15)) (justify left bottom) hide)
    )
    (property "Author" "Antmicro" (at 267.335 58.42 0)
      (effects (font (size 1.27 1.27) (thickness 0.15)) (justify left bottom) hide)
    )
    (property "License" "Apache-2.0" (at 267.335 60.96 0)
      (effects (font (size 1.27 1.27) (thickness 0.15)) (justify left bottom) hide)
    )
    (pin "1")
    (instances
      (project "kria-k26-devboard"
        (path ""
          (reference "#PWR0142") (unit 1)
        )
      )
    )
  )

  (symbol (lib_id "kria-k26-devboard:R_2k2_0402") (at 95.25 239.395 180) (unit 1)
    (in_bom yes) (on_board yes) (dnp no)
    (property "Reference" "R120" (at 87.63 238.125 0)
      (effects (font (size 1.524 1.524)))
    )
    (property "Value" "R_2k2_0402" (at 95.25 235.585 0)
      (effects (font (size 1.27 1.27) (thickness 0.15)) (justify left bottom) hide)
    )
    (property "Footprint" "kria-k26-devboard-footprints:R_0402_1005Metric" (at 90.17 244.475 0)
      (effects (font (size 1.27 1.27) (thickness 0.15)) (justify left bottom) hide)
    )
    (property "Datasheet" "https://www.bourns.com/docs/product-datasheets/cr.pdf" (at 95.25 239.395 0)
      (effects (font (size 1.27 1.27) (thickness 0.15)) (justify left bottom) hide)
    )
    (property "Manufacturer" "Bourns" (at 90.17 249.555 0)
      (effects (font (size 1.27 1.27) (thickness 0.15)) (justify left bottom) hide)
    )
    (property "MPN" "CR0402-FX-2201GLF" (at 90.17 247.015 0)
      (effects (font (size 1.27 1.27) (thickness 0.15)) (justify left bottom) hide)
    )
    (property "Val" "2k2" (at 87.63 240.665 0)
      (effects (font (size 1.27 1.27) (thickness 0.15)))
    )
    (property "License" "Apache-2.0" (at 74.93 213.995 0)
      (effects (font (size 1.27 1.27) (thickness 0.15)) (justify left bottom) hide)
    )
    (property "Author" "Antmicro" (at 74.93 211.455 0)
      (effects (font (size 1.27 1.27) (thickness 0.15)) (justify left bottom) hide)
    )
    (property "Tolerance" "1%" (at 74.93 229.235 0)
      (effects (font (size 1.27 1.27)) (justify left bottom) hide)
    )
    (pin "1")
    (pin "2")
    (instances
      (project "kria-k26-devboard"
        (path ""
          (reference "R120") (unit 1)
        )
      )
    )
  )

  (symbol (lib_id "kria-k26-devboard:GND") (at 117.475 55.88 0) (unit 1)
    (in_bom yes) (on_board yes) (dnp no) (fields_autoplaced)
    (property "Reference" "#PWR0138" (at 117.475 62.23 0)
      (effects (font (size 1.27 1.27)) hide)
    )
    (property "Value" "GND" (at 117.475 60.325 0)
      (effects (font (size 1.27 1.27)))
    )
    (property "Footprint" "" (at 126.365 63.5 0)
      (effects (font (size 1.27 1.27) (thickness 0.15)) (justify left bottom) hide)
    )
    (property "Datasheet" "" (at 126.365 68.58 0)
      (effects (font (size 1.27 1.27) (thickness 0.15)) (justify left bottom) hide)
    )
    (property "Author" "Antmicro" (at 126.365 63.5 0)
      (effects (font (size 1.27 1.27) (thickness 0.15)) (justify left bottom) hide)
    )
    (property "License" "Apache-2.0" (at 126.365 66.04 0)
      (effects (font (size 1.27 1.27) (thickness 0.15)) (justify left bottom) hide)
    )
    (pin "1")
    (instances
      (project "kria-k26-devboard"
        (path ""
          (reference "#PWR0138") (unit 1)
        )
      )
    )
  )

  (symbol (lib_id "kria-k26-devboard:GND") (at 257.81 130.175 0) (unit 1)
    (in_bom yes) (on_board yes) (dnp no) (fields_autoplaced)
    (property "Reference" "#PWR0157" (at 257.81 136.525 0)
      (effects (font (size 1.27 1.27)) hide)
    )
    (property "Value" "GND" (at 257.81 135.255 0)
      (effects (font (size 1.27 1.27)))
    )
    (property "Footprint" "" (at 266.7 137.795 0)
      (effects (font (size 1.27 1.27) (thickness 0.15)) (justify left bottom) hide)
    )
    (property "Datasheet" "" (at 266.7 142.875 0)
      (effects (font (size 1.27 1.27) (thickness 0.15)) (justify left bottom) hide)
    )
    (property "Author" "Antmicro" (at 266.7 137.795 0)
      (effects (font (size 1.27 1.27) (thickness 0.15)) (justify left bottom) hide)
    )
    (property "License" "Apache-2.0" (at 266.7 140.335 0)
      (effects (font (size 1.27 1.27) (thickness 0.15)) (justify left bottom) hide)
    )
    (pin "1")
    (instances
      (project "kria-k26-devboard"
        (path ""
          (reference "#PWR0157") (unit 1)
        )
      )
    )
  )

  (symbol (lib_id "kria-k26-devboard:R_2k2_0402") (at 95.25 245.11 180) (unit 1)
    (in_bom yes) (on_board yes) (dnp no)
    (property "Reference" "R121" (at 87.884 243.84 0)
      (effects (font (size 1.524 1.524)))
    )
    (property "Value" "R_2k2_0402" (at 95.25 241.3 0)
      (effects (font (size 1.27 1.27) (thickness 0.15)) (justify left bottom) hide)
    )
    (property "Footprint" "kria-k26-devboard-footprints:R_0402_1005Metric" (at 90.17 250.19 0)
      (effects (font (size 1.27 1.27) (thickness 0.15)) (justify left bottom) hide)
    )
    (property "Datasheet" "https://www.bourns.com/docs/product-datasheets/cr.pdf" (at 95.25 245.11 0)
      (effects (font (size 1.27 1.27) (thickness 0.15)) (justify left bottom) hide)
    )
    (property "Manufacturer" "Bourns" (at 90.17 255.27 0)
      (effects (font (size 1.27 1.27) (thickness 0.15)) (justify left bottom) hide)
    )
    (property "MPN" "CR0402-FX-2201GLF" (at 90.17 252.73 0)
      (effects (font (size 1.27 1.27) (thickness 0.15)) (justify left bottom) hide)
    )
    (property "Val" "2k2" (at 87.884 246.38 0)
      (effects (font (size 1.27 1.27) (thickness 0.15)))
    )
    (property "License" "Apache-2.0" (at 74.93 219.71 0)
      (effects (font (size 1.27 1.27) (thickness 0.15)) (justify left bottom) hide)
    )
    (property "Author" "Antmicro" (at 74.93 217.17 0)
      (effects (font (size 1.27 1.27) (thickness 0.15)) (justify left bottom) hide)
    )
    (property "Tolerance" "1%" (at 74.93 234.95 0)
      (effects (font (size 1.27 1.27)) (justify left bottom) hide)
    )
    (pin "1")
    (pin "2")
    (instances
      (project "kria-k26-devboard"
        (path ""
          (reference "R121") (unit 1)
        )
      )
    )
  )

  (symbol (lib_id "kria-k26-devboard:C_22u_16V_0603") (at 107.95 50.8 270) (unit 1)
    (in_bom yes) (on_board yes) (dnp no)
    (property "Reference" "C195" (at 108.585 51.435 90)
      (effects (font (size 1.524 1.524)) (justify left))
    )
    (property "Value" "C_22u_16V_0603" (at 104.14 50.8 0)
      (effects (font (size 1.524 1.524)) hide)
    )
    (property "Footprint" "kria-k26-devboard-footprints:C_0603_1608Metric" (at 113.03 55.88 0)
      (effects (font (size 1.27 1.27) (thickness 0.15)) (justify left bottom) hide)
    )
    (property "Datasheet" "https://www.mouser.pl/datasheet/2/585/MLCC-1837944.pdf" (at 107.95 50.8 0)
      (effects (font (size 1.27 1.27) (thickness 0.15)) (justify left bottom) hide)
    )
    (property "Manufacturer" "Samsung" (at 118.11 55.88 0)
      (effects (font (size 1.27 1.27) (thickness 0.15)) (justify left bottom) hide)
    )
    (property "MPN" "CL10A226MO7JZNC" (at 115.57 55.88 0)
      (effects (font (size 1.27 1.27) (thickness 0.15)) (justify left bottom) hide)
    )
    (property "Val" "22u/16V" (at 108.585 55.245 90)
      (effects (font (size 1.27 1.27) (thickness 0.15)) (justify left))
    )
    (property "License" "Apache-2.0" (at 85.09 71.12 0)
      (effects (font (size 1.27 1.27) (thickness 0.15)) (justify left bottom) hide)
    )
    (property "Author" "Antmicro" (at 82.55 71.12 0)
      (effects (font (size 1.27 1.27) (thickness 0.15)) (justify left bottom) hide)
    )
    (property "Voltage" "" (at 80.01 71.12 0)
      (effects (font (size 1.27 1.27)) (justify left bottom) hide)
    )
    (property "Dielectric" "" (at 77.47 71.12 0)
      (effects (font (size 1.27 1.27)) (justify left bottom) hide)
    )
    (pin "1")
    (pin "2")
    (instances
      (project "kria-k26-devboard"
        (path ""
          (reference "C195") (unit 1)
        )
      )
    )
  )

  (symbol (lib_id "kria-k26-devboard:R_0R_22.4A_0603") (at 260.985 113.03 0) (unit 1)
    (in_bom yes) (on_board yes) (dnp no)
    (property "Reference" "R164" (at 263.525 109.22 0)
      (effects (font (size 1.524 1.524)))
    )
    (property "Value" "R_0R_22.4A_0603" (at 260.985 116.84 0)
      (effects (font (size 1.27 1.27) (thickness 0.15)) (justify left bottom) hide)
    )
    (property "Footprint" "kria-k26-devboard-footprints:R_0603_1608Metric" (at 266.065 107.95 0)
      (effects (font (size 1.27 1.27) (thickness 0.15)) (justify left bottom) hide)
    )
    (property "Datasheet" "https://fscdn.rohm.com/en/products/databook/datasheet/passive/resistor/chip_resistor/pmr-jpw-e.pdf" (at 260.985 113.03 0)
      (effects (font (size 1.27 1.27) (thickness 0.15)) (justify left bottom) hide)
    )
    (property "Manufacturer" "ROHM Semiconductor" (at 266.065 102.87 0)
      (effects (font (size 1.27 1.27) (thickness 0.15)) (justify left bottom) hide)
    )
    (property "MPN" "PMR03EZPJ000" (at 266.065 105.41 0)
      (effects (font (size 1.27 1.27) (thickness 0.15)) (justify left bottom) hide)
    )
    (property "Val" "0R" (at 263.525 111.125 0)
      (effects (font (size 1.27 1.27) (thickness 0.15)))
    )
    (property "Author" "Antmicro" (at 283.845 135.89 0)
      (effects (font (size 1.27 1.27) (thickness 0.15)) (justify left bottom) hide)
    )
    (property "License" "Apache-2.0" (at 283.845 138.43 0)
      (effects (font (size 1.27 1.27) (thickness 0.15)) (justify left bottom) hide)
    )
    (property "Max. Curr." "22.4A" (at 263.525 114.935 0)
      (effects (font (size 1.27 1.27) (thickness 0.15)))
    )
    (pin "1")
    (pin "2")
    (instances
      (project "kria-k26-devboard"
        (path ""
          (reference "R164") (unit 1)
        )
      )
    )
  )

  (symbol (lib_id "kria-k26-devboard:GND") (at 236.855 88.9 0) (unit 1)
    (in_bom yes) (on_board yes) (dnp no) (fields_autoplaced)
    (property "Reference" "#PWR0153" (at 236.855 95.25 0)
      (effects (font (size 1.27 1.27)) hide)
    )
    (property "Value" "GND" (at 236.855 93.98 0)
      (effects (font (size 1.27 1.27)))
    )
    (property "Footprint" "" (at 245.745 96.52 0)
      (effects (font (size 1.27 1.27) (thickness 0.15)) (justify left bottom) hide)
    )
    (property "Datasheet" "" (at 245.745 101.6 0)
      (effects (font (size 1.27 1.27) (thickness 0.15)) (justify left bottom) hide)
    )
    (property "Author" "Antmicro" (at 245.745 96.52 0)
      (effects (font (size 1.27 1.27) (thickness 0.15)) (justify left bottom) hide)
    )
    (property "License" "Apache-2.0" (at 245.745 99.06 0)
      (effects (font (size 1.27 1.27) (thickness 0.15)) (justify left bottom) hide)
    )
    (pin "1")
    (instances
      (project "kria-k26-devboard"
        (path ""
          (reference "#PWR0153") (unit 1)
        )
      )
    )
  )

  (symbol (lib_id "kria-k26-devboard:GND") (at 320.04 46.355 0) (unit 1)
    (in_bom yes) (on_board yes) (dnp no) (fields_autoplaced)
    (property "Reference" "#PWR0143" (at 320.04 52.705 0)
      (effects (font (size 1.27 1.27)) hide)
    )
    (property "Value" "GND" (at 320.04 51.435 0)
      (effects (font (size 1.27 1.27)))
    )
    (property "Footprint" "" (at 328.93 53.975 0)
      (effects (font (size 1.27 1.27) (thickness 0.15)) (justify left bottom) hide)
    )
    (property "Datasheet" "" (at 328.93 59.055 0)
      (effects (font (size 1.27 1.27) (thickness 0.15)) (justify left bottom) hide)
    )
    (property "Author" "Antmicro" (at 328.93 53.975 0)
      (effects (font (size 1.27 1.27) (thickness 0.15)) (justify left bottom) hide)
    )
    (property "License" "Apache-2.0" (at 328.93 56.515 0)
      (effects (font (size 1.27 1.27) (thickness 0.15)) (justify left bottom) hide)
    )
    (pin "1")
    (instances
      (project "kria-k26-devboard"
        (path ""
          (reference "#PWR0143") (unit 1)
        )
      )
    )
  )

  (symbol (lib_id "kria-k26-devboard:GND") (at 127 55.88 0) (unit 1)
    (in_bom yes) (on_board yes) (dnp no) (fields_autoplaced)
    (property "Reference" "#PWR0139" (at 127 62.23 0)
      (effects (font (size 1.27 1.27)) hide)
    )
    (property "Value" "GND" (at 127 60.325 0)
      (effects (font (size 1.27 1.27)))
    )
    (property "Footprint" "" (at 135.89 63.5 0)
      (effects (font (size 1.27 1.27) (thickness 0.15)) (justify left bottom) hide)
    )
    (property "Datasheet" "" (at 135.89 68.58 0)
      (effects (font (size 1.27 1.27) (thickness 0.15)) (justify left bottom) hide)
    )
    (property "Author" "Antmicro" (at 135.89 63.5 0)
      (effects (font (size 1.27 1.27) (thickness 0.15)) (justify left bottom) hide)
    )
    (property "License" "Apache-2.0" (at 135.89 66.04 0)
      (effects (font (size 1.27 1.27) (thickness 0.15)) (justify left bottom) hide)
    )
    (pin "1")
    (instances
      (project "kria-k26-devboard"
        (path ""
          (reference "#PWR0139") (unit 1)
        )
      )
    )
  )

  (symbol (lib_id "kria-k26-devboard:GND") (at 196.85 45.72 0) (unit 1)
    (in_bom yes) (on_board yes) (dnp no) (fields_autoplaced)
    (property "Reference" "#PWR0148" (at 196.85 52.07 0)
      (effects (font (size 1.27 1.27)) hide)
    )
    (property "Value" "GND" (at 196.85 50.8 0)
      (effects (font (size 1.27 1.27)))
    )
    (property "Footprint" "" (at 205.74 53.34 0)
      (effects (font (size 1.27 1.27) (thickness 0.15)) (justify left bottom) hide)
    )
    (property "Datasheet" "" (at 205.74 58.42 0)
      (effects (font (size 1.27 1.27) (thickness 0.15)) (justify left bottom) hide)
    )
    (property "Author" "Antmicro" (at 205.74 53.34 0)
      (effects (font (size 1.27 1.27) (thickness 0.15)) (justify left bottom) hide)
    )
    (property "License" "Apache-2.0" (at 205.74 55.88 0)
      (effects (font (size 1.27 1.27) (thickness 0.15)) (justify left bottom) hide)
    )
    (pin "1")
    (instances
      (project "kria-k26-devboard"
        (path ""
          (reference "#PWR0148") (unit 1)
        )
      )
    )
  )

  (symbol (lib_id "kria-k26-devboard:GND") (at 196.85 163.83 0) (unit 1)
    (in_bom yes) (on_board yes) (dnp no) (fields_autoplaced)
    (property "Reference" "#PWR0161" (at 196.85 170.18 0)
      (effects (font (size 1.27 1.27)) hide)
    )
    (property "Value" "GND" (at 196.85 168.91 0)
      (effects (font (size 1.27 1.27)))
    )
    (property "Footprint" "" (at 205.74 171.45 0)
      (effects (font (size 1.27 1.27) (thickness 0.15)) (justify left bottom) hide)
    )
    (property "Datasheet" "" (at 205.74 176.53 0)
      (effects (font (size 1.27 1.27) (thickness 0.15)) (justify left bottom) hide)
    )
    (property "Author" "Antmicro" (at 205.74 171.45 0)
      (effects (font (size 1.27 1.27) (thickness 0.15)) (justify left bottom) hide)
    )
    (property "License" "Apache-2.0" (at 205.74 173.99 0)
      (effects (font (size 1.27 1.27) (thickness 0.15)) (justify left bottom) hide)
    )
    (pin "1")
    (instances
      (project "kria-k26-devboard"
        (path ""
          (reference "#PWR0161") (unit 1)
        )
      )
    )
  )

  (symbol (lib_id "kria-k26-devboard:GND") (at 97.155 55.88 0) (unit 1)
    (in_bom yes) (on_board yes) (dnp no) (fields_autoplaced)
    (property "Reference" "#PWR0136" (at 97.155 62.23 0)
      (effects (font (size 1.27 1.27)) hide)
    )
    (property "Value" "GND" (at 97.155 60.325 0)
      (effects (font (size 1.27 1.27)))
    )
    (property "Footprint" "" (at 106.045 63.5 0)
      (effects (font (size 1.27 1.27) (thickness 0.15)) (justify left bottom) hide)
    )
    (property "Datasheet" "" (at 106.045 68.58 0)
      (effects (font (size 1.27 1.27) (thickness 0.15)) (justify left bottom) hide)
    )
    (property "Author" "Antmicro" (at 106.045 63.5 0)
      (effects (font (size 1.27 1.27) (thickness 0.15)) (justify left bottom) hide)
    )
    (property "License" "Apache-2.0" (at 106.045 66.04 0)
      (effects (font (size 1.27 1.27) (thickness 0.15)) (justify left bottom) hide)
    )
    (pin "1")
    (instances
      (project "kria-k26-devboard"
        (path ""
          (reference "#PWR0136") (unit 1)
        )
      )
    )
  )

  (symbol (lib_id "kria-k26-devboard:R_0R_22.4A_0603") (at 262.255 34.29 0) (unit 1)
    (in_bom yes) (on_board yes) (dnp no)
    (property "Reference" "R162" (at 264.795 30.48 0)
      (effects (font (size 1.524 1.524)))
    )
    (property "Value" "R_0R_22.4A_0603" (at 262.255 38.1 0)
      (effects (font (size 1.27 1.27) (thickness 0.15)) (justify left bottom) hide)
    )
    (property "Footprint" "kria-k26-devboard-footprints:R_0603_1608Metric" (at 267.335 29.21 0)
      (effects (font (size 1.27 1.27) (thickness 0.15)) (justify left bottom) hide)
    )
    (property "Datasheet" "https://fscdn.rohm.com/en/products/databook/datasheet/passive/resistor/chip_resistor/pmr-jpw-e.pdf" (at 262.255 34.29 0)
      (effects (font (size 1.27 1.27) (thickness 0.15)) (justify left bottom) hide)
    )
    (property "Manufacturer" "ROHM Semiconductor" (at 267.335 24.13 0)
      (effects (font (size 1.27 1.27) (thickness 0.15)) (justify left bottom) hide)
    )
    (property "MPN" "PMR03EZPJ000" (at 267.335 26.67 0)
      (effects (font (size 1.27 1.27) (thickness 0.15)) (justify left bottom) hide)
    )
    (property "Val" "0R" (at 264.795 32.385 0)
      (effects (font (size 1.27 1.27) (thickness 0.15)))
    )
    (property "Author" "Antmicro" (at 285.115 57.15 0)
      (effects (font (size 1.27 1.27) (thickness 0.15)) (justify left bottom) hide)
    )
    (property "License" "Apache-2.0" (at 285.115 59.69 0)
      (effects (font (size 1.27 1.27) (thickness 0.15)) (justify left bottom) hide)
    )
    (property "Max. Curr." "22.4A" (at 264.795 36.195 0)
      (effects (font (size 1.27 1.27) (thickness 0.15)))
    )
    (pin "1")
    (pin "2")
    (instances
      (project "kria-k26-devboard"
        (path ""
          (reference "R162") (unit 1)
        )
      )
    )
  )

  (symbol (lib_id "kria-k26-devboard:R_147k_0402") (at 97.155 43.18 270) (unit 1)
    (in_bom yes) (on_board yes) (dnp no) (fields_autoplaced)
    (property "Reference" "R122" (at 99.695 44.45 90)
      (effects (font (size 1.524 1.524)) (justify left))
    )
    (property "Value" "R_147k_0402" (at 93.345 43.18 0)
      (effects (font (size 1.524 1.524)) hide)
    )
    (property "Footprint" "kria-k26-devboard-footprints:R_0402_1005Metric" (at 102.235 48.26 0)
      (effects (font (size 1.27 1.27) (thickness 0.15)) (justify left bottom) hide)
    )
    (property "Datasheet" "https://www.bourns.com/docs/product-datasheets/cr.pdf" (at 97.155 43.18 0)
      (effects (font (size 1.27 1.27) (thickness 0.15)) (justify left bottom) hide)
    )
    (property "Manufacturer" "Bourns" (at 107.315 48.26 0)
      (effects (font (size 1.27 1.27) (thickness 0.15)) (justify left bottom) hide)
    )
    (property "MPN" "CR0402-FX-1473GLF" (at 104.775 48.26 0)
      (effects (font (size 1.27 1.27) (thickness 0.15)) (justify left bottom) hide)
    )
    (property "Val" "147k" (at 99.695 47.6249 90)
      (effects (font (size 1.27 1.27) (thickness 0.15)) (justify left))
    )
    (property "License" "Apache-2.0" (at 71.755 63.5 0)
      (effects (font (size 1.27 1.27) (thickness 0.15)) (justify left bottom) hide)
    )
    (property "Author" "Antmicro" (at 69.215 63.5 0)
      (effects (font (size 1.27 1.27) (thickness 0.15)) (justify left bottom) hide)
    )
    (property "Tolerance" "1%" (at 86.995 63.5 0)
      (effects (font (size 1.27 1.27)) (justify left bottom) hide)
    )
    (pin "1")
    (pin "2")
    (instances
      (project "kria-k26-devboard"
        (path ""
          (reference "R122") (unit 1)
        )
      )
    )
  )

  (symbol (lib_id "kria-k26-devboard:R_0R_0402") (at 94.615 149.225 180) (unit 1)
    (in_bom no) (on_board yes) (dnp yes)
    (property "Reference" "R166" (at 92.075 144.78 0)
      (effects (font (size 1.524 1.524)))
    )
    (property "Value" "R_0R_0402" (at 94.615 145.415 0)
      (effects (font (size 1.524 1.524)) hide)
    )
    (property "Footprint" "kria-k26-devboard-footprints:R_0402_1005Metric" (at 89.535 154.305 0)
      (effects (font (size 1.27 1.27) (thickness 0.15)) (justify left bottom) hide)
    )
    (property "Datasheet" "https://industrial.panasonic.com/cdbs/www-data/pdf/RDA0000/AOA0000C301.pdf" (at 94.615 149.225 0)
      (effects (font (size 1.27 1.27) (thickness 0.15)) (justify left bottom) hide)
    )
    (property "Manufacturer" "Panasonic" (at 89.535 159.385 0)
      (effects (font (size 1.27 1.27) (thickness 0.15)) (justify left bottom) hide)
    )
    (property "MPN" "ERJ2GE0R00X" (at 89.535 156.845 0)
      (effects (font (size 1.27 1.27) (thickness 0.15)) (justify left bottom) hide)
    )
    (property "Val" "0R" (at 92.075 147.32 0)
      (effects (font (size 1.27 1.27) (thickness 0.15)))
    )
    (property "License" "Apache-2.0" (at 74.295 123.825 0)
      (effects (font (size 1.27 1.27) (thickness 0.15)) (justify left bottom) hide)
    )
    (property "Author" "Antmicro" (at 74.295 121.285 0)
      (effects (font (size 1.27 1.27) (thickness 0.15)) (justify left bottom) hide)
    )
    (property "Tolerance" "~" (at 74.295 139.065 0)
      (effects (font (size 1.27 1.27)) (justify left bottom) hide)
    )
    (property "Current" "1A" (at 74.295 118.745 0)
      (effects (font (size 1.27 1.27) (thickness 0.15)) (justify left bottom) hide)
    )
    (property "DNP" "DNP" (at 92.075 149.225 0)
      (effects (font (size 1.27 1.27)))
    )
    (pin "1")
    (pin "2")
    (instances
      (project "kria-k26-devboard"
        (path ""
          (reference "R166") (unit 1)
        )
      )
    )
  )

  (symbol (lib_id "kria-k26-devboard:GND") (at 236.855 50.8 0) (unit 1)
    (in_bom yes) (on_board yes) (dnp no) (fields_autoplaced)
    (property "Reference" "#PWR0141" (at 236.855 57.15 0)
      (effects (font (size 1.27 1.27)) hide)
    )
    (property "Value" "GND" (at 236.855 55.88 0)
      (effects (font (size 1.27 1.27)))
    )
    (property "Footprint" "" (at 245.745 58.42 0)
      (effects (font (size 1.27 1.27) (thickness 0.15)) (justify left bottom) hide)
    )
    (property "Datasheet" "" (at 245.745 63.5 0)
      (effects (font (size 1.27 1.27) (thickness 0.15)) (justify left bottom) hide)
    )
    (property "Author" "Antmicro" (at 245.745 58.42 0)
      (effects (font (size 1.27 1.27) (thickness 0.15)) (justify left bottom) hide)
    )
    (property "License" "Apache-2.0" (at 245.745 60.96 0)
      (effects (font (size 1.27 1.27) (thickness 0.15)) (justify left bottom) hide)
    )
    (pin "1")
    (instances
      (project "kria-k26-devboard"
        (path ""
          (reference "#PWR0141") (unit 1)
        )
      )
    )
  )

  (symbol (lib_id "kria-k26-devboard:R_0R_22.4A_0603") (at 253.365 193.04 0) (unit 1)
    (in_bom yes) (on_board yes) (dnp no)
    (property "Reference" "R157" (at 255.905 189.23 0)
      (effects (font (size 1.524 1.524)))
    )
    (property "Value" "R_0R_22.4A_0603" (at 253.365 196.85 0)
      (effects (font (size 1.27 1.27) (thickness 0.15)) (justify left bottom) hide)
    )
    (property "Footprint" "kria-k26-devboard-footprints:R_0603_1608Metric" (at 258.445 187.96 0)
      (effects (font (size 1.27 1.27) (thickness 0.15)) (justify left bottom) hide)
    )
    (property "Datasheet" "https://fscdn.rohm.com/en/products/databook/datasheet/passive/resistor/chip_resistor/pmr-jpw-e.pdf" (at 253.365 193.04 0)
      (effects (font (size 1.27 1.27) (thickness 0.15)) (justify left bottom) hide)
    )
    (property "Manufacturer" "ROHM Semiconductor" (at 258.445 182.88 0)
      (effects (font (size 1.27 1.27) (thickness 0.15)) (justify left bottom) hide)
    )
    (property "MPN" "PMR03EZPJ000" (at 258.445 185.42 0)
      (effects (font (size 1.27 1.27) (thickness 0.15)) (justify left bottom) hide)
    )
    (property "Val" "0R" (at 255.905 191.135 0)
      (effects (font (size 1.27 1.27) (thickness 0.15)))
    )
    (property "Author" "Antmicro" (at 276.225 215.9 0)
      (effects (font (size 1.27 1.27) (thickness 0.15)) (justify left bottom) hide)
    )
    (property "License" "Apache-2.0" (at 276.225 218.44 0)
      (effects (font (size 1.27 1.27) (thickness 0.15)) (justify left bottom) hide)
    )
    (property "Max. Curr." "22.4A" (at 255.905 194.945 0)
      (effects (font (size 1.27 1.27) (thickness 0.15)))
    )
    (pin "1")
    (pin "2")
    (instances
      (project "kria-k26-devboard"
        (path ""
          (reference "R157") (unit 1)
        )
      )
    )
  )

  (symbol (lib_id "kria-k26-devboard:RT6236AHGQUF") (at 56.515 89.535 0) (unit 1)
    (in_bom yes) (on_board yes) (dnp no) (fields_autoplaced)
    (property "Reference" "U48" (at 65.405 81.28 0)
      (effects (font (size 1.27 1.27)))
    )
    (property "Value" "RT6236AHGQUF" (at 65.405 83.82 0)
      (effects (font (size 1.27 1.27) (thickness 0.15)))
    )
    (property "Footprint" "kria-k26-devboard-footprints:UQFN-13_2x3mm_P0.5mm" (at 89.535 97.155 0)
      (effects (font (size 1.27 1.27) (thickness 0.15)) (justify left bottom) hide)
    )
    (property "Datasheet" "https://www.richtek.com/assets/product_file/RT6236A=RT6236B/DS6236AB-02.pdf" (at 89.535 99.695 0)
      (effects (font (size 1.27 1.27) (thickness 0.15)) (justify left bottom) hide)
    )
    (property "MPN" "RT6236AHGQUF" (at 89.535 102.235 0)
      (effects (font (size 1.27 1.27) (thickness 0.15)) (justify left bottom) hide)
    )
    (property "Manufacturer" "Richtek" (at 89.535 104.775 0)
      (effects (font (size 1.27 1.27) (thickness 0.15)) (justify left bottom) hide)
    )
    (property "Author" "Antmicro" (at 89.535 107.315 0)
      (effects (font (size 1.27 1.27) (thickness 0.15)) (justify left bottom) hide)
    )
    (property "License" "Apache-2.0" (at 89.535 109.855 0)
      (effects (font (size 1.27 1.27) (thickness 0.15)) (justify left bottom) hide)
    )
    (pin "1")
    (pin "10")
    (pin "11")
    (pin "12")
    (pin "13")
    (pin "2")
    (pin "3")
    (pin "4")
    (pin "5")
    (pin "6")
    (pin "7")
    (pin "8")
    (pin "9")
    (instances
      (project "kria-k26-devboard"
        (path ""
          (reference "U48") (unit 1)
        )
      )
    )
  )

  (symbol (lib_id "kria-k26-devboard:C_22u_16V_0603") (at 106.68 106.045 270) (unit 1)
    (in_bom yes) (on_board yes) (dnp no)
    (property "Reference" "C196" (at 107.315 106.68 90)
      (effects (font (size 1.524 1.524)) (justify left))
    )
    (property "Value" "C_22u_16V_0603" (at 102.87 106.045 0)
      (effects (font (size 1.524 1.524)) hide)
    )
    (property "Footprint" "kria-k26-devboard-footprints:C_0603_1608Metric" (at 111.76 111.125 0)
      (effects (font (size 1.27 1.27) (thickness 0.15)) (justify left bottom) hide)
    )
    (property "Datasheet" "https://www.mouser.pl/datasheet/2/585/MLCC-1837944.pdf" (at 106.68 106.045 0)
      (effects (font (size 1.27 1.27) (thickness 0.15)) (justify left bottom) hide)
    )
    (property "Manufacturer" "Samsung" (at 116.84 111.125 0)
      (effects (font (size 1.27 1.27) (thickness 0.15)) (justify left bottom) hide)
    )
    (property "MPN" "CL10A226MO7JZNC" (at 114.3 111.125 0)
      (effects (font (size 1.27 1.27) (thickness 0.15)) (justify left bottom) hide)
    )
    (property "Val" "22u/16V" (at 107.315 110.49 90)
      (effects (font (size 1.27 1.27) (thickness 0.15)) (justify left))
    )
    (property "License" "Apache-2.0" (at 83.82 126.365 0)
      (effects (font (size 1.27 1.27) (thickness 0.15)) (justify left bottom) hide)
    )
    (property "Author" "Antmicro" (at 81.28 126.365 0)
      (effects (font (size 1.27 1.27) (thickness 0.15)) (justify left bottom) hide)
    )
    (property "Voltage" "" (at 78.74 126.365 0)
      (effects (font (size 1.27 1.27)) (justify left bottom) hide)
    )
    (property "Dielectric" "" (at 76.2 126.365 0)
      (effects (font (size 1.27 1.27)) (justify left bottom) hide)
    )
    (pin "1")
    (pin "2")
    (instances
      (project "kria-k26-devboard"
        (path ""
          (reference "C196") (unit 1)
        )
      )
    )
  )

  (symbol (lib_id "kria-k26-devboard:R_0R_22.4A_0603") (at 261.62 72.39 0) (unit 1)
    (in_bom yes) (on_board yes) (dnp no)
    (property "Reference" "R163" (at 264.16 68.58 0)
      (effects (font (size 1.524 1.524)))
    )
    (property "Value" "R_0R_22.4A_0603" (at 261.62 76.2 0)
      (effects (font (size 1.27 1.27) (thickness 0.15)) (justify left bottom) hide)
    )
    (property "Footprint" "kria-k26-devboard-footprints:R_0603_1608Metric" (at 266.7 67.31 0)
      (effects (font (size 1.27 1.27) (thickness 0.15)) (justify left bottom) hide)
    )
    (property "Datasheet" "https://fscdn.rohm.com/en/products/databook/datasheet/passive/resistor/chip_resistor/pmr-jpw-e.pdf" (at 261.62 72.39 0)
      (effects (font (size 1.27 1.27) (thickness 0.15)) (justify left bottom) hide)
    )
    (property "Manufacturer" "ROHM Semiconductor" (at 266.7 62.23 0)
      (effects (font (size 1.27 1.27) (thickness 0.15)) (justify left bottom) hide)
    )
    (property "MPN" "PMR03EZPJ000" (at 266.7 64.77 0)
      (effects (font (size 1.27 1.27) (thickness 0.15)) (justify left bottom) hide)
    )
    (property "Val" "0R" (at 264.16 70.485 0)
      (effects (font (size 1.27 1.27) (thickness 0.15)))
    )
    (property "Author" "Antmicro" (at 284.48 95.25 0)
      (effects (font (size 1.27 1.27) (thickness 0.15)) (justify left bottom) hide)
    )
    (property "License" "Apache-2.0" (at 284.48 97.79 0)
      (effects (font (size 1.27 1.27) (thickness 0.15)) (justify left bottom) hide)
    )
    (property "Max. Curr." "22.4A" (at 264.16 74.295 0)
      (effects (font (size 1.27 1.27) (thickness 0.15)))
    )
    (pin "1")
    (pin "2")
    (instances
      (project "kria-k26-devboard"
        (path ""
          (reference "R163") (unit 1)
        )
      )
    )
  )

  (symbol (lib_id "kria-k26-devboard:GND") (at 360.68 85.09 0) (unit 1)
    (in_bom yes) (on_board yes) (dnp no) (fields_autoplaced)
    (property "Reference" "#PWR0152" (at 360.68 91.44 0)
      (effects (font (size 1.27 1.27)) hide)
    )
    (property "Value" "GND" (at 360.68 90.17 0)
      (effects (font (size 1.27 1.27)))
    )
    (property "Footprint" "" (at 369.57 92.71 0)
      (effects (font (size 1.27 1.27) (thickness 0.15)) (justify left bottom) hide)
    )
    (property "Datasheet" "" (at 369.57 97.79 0)
      (effects (font (size 1.27 1.27) (thickness 0.15)) (justify left bottom) hide)
    )
    (property "Author" "Antmicro" (at 369.57 92.71 0)
      (effects (font (size 1.27 1.27) (thickness 0.15)) (justify left bottom) hide)
    )
    (property "License" "Apache-2.0" (at 369.57 95.25 0)
      (effects (font (size 1.27 1.27) (thickness 0.15)) (justify left bottom) hide)
    )
    (pin "1")
    (instances
      (project "kria-k26-devboard"
        (path ""
          (reference "#PWR0152") (unit 1)
        )
      )
    )
  )

  (symbol (lib_id "kria-k26-devboard:GND") (at 248.92 50.8 0) (unit 1)
    (in_bom yes) (on_board yes) (dnp no) (fields_autoplaced)
    (property "Reference" "#PWR0140" (at 248.92 57.15 0)
      (effects (font (size 1.27 1.27)) hide)
    )
    (property "Value" "GND" (at 248.92 55.88 0)
      (effects (font (size 1.27 1.27)))
    )
    (property "Footprint" "" (at 257.81 58.42 0)
      (effects (font (size 1.27 1.27) (thickness 0.15)) (justify left bottom) hide)
    )
    (property "Datasheet" "" (at 257.81 63.5 0)
      (effects (font (size 1.27 1.27) (thickness 0.15)) (justify left bottom) hide)
    )
    (property "Author" "Antmicro" (at 257.81 58.42 0)
      (effects (font (size 1.27 1.27) (thickness 0.15)) (justify left bottom) hide)
    )
    (property "License" "Apache-2.0" (at 257.81 60.96 0)
      (effects (font (size 1.27 1.27) (thickness 0.15)) (justify left bottom) hide)
    )
    (pin "1")
    (instances
      (project "kria-k26-devboard"
        (path ""
          (reference "#PWR0140") (unit 1)
        )
      )
    )
  )

  (symbol (lib_id "kria-k26-devboard:GND") (at 106.68 111.125 0) (unit 1)
    (in_bom yes) (on_board yes) (dnp no) (fields_autoplaced)
    (property "Reference" "#PWR0132" (at 106.68 117.475 0)
      (effects (font (size 1.27 1.27)) hide)
    )
    (property "Value" "GND" (at 106.68 115.57 0)
      (effects (font (size 1.27 1.27)))
    )
    (property "Footprint" "" (at 115.57 118.745 0)
      (effects (font (size 1.27 1.27) (thickness 0.15)) (justify left bottom) hide)
    )
    (property "Datasheet" "" (at 115.57 123.825 0)
      (effects (font (size 1.27 1.27) (thickness 0.15)) (justify left bottom) hide)
    )
    (property "Author" "Antmicro" (at 115.57 118.745 0)
      (effects (font (size 1.27 1.27) (thickness 0.15)) (justify left bottom) hide)
    )
    (property "License" "Apache-2.0" (at 115.57 121.285 0)
      (effects (font (size 1.27 1.27) (thickness 0.15)) (justify left bottom) hide)
    )
    (pin "1")
    (instances
      (project "kria-k26-devboard"
        (path ""
          (reference "#PWR0132") (unit 1)
        )
      )
    )
  )

  (symbol (lib_id "kria-k26-devboard:R_0R_0402") (at 89.535 141.605 0) (unit 1)
    (in_bom yes) (on_board yes) (dnp no)
    (property "Reference" "R165" (at 92.075 137.16 0)
      (effects (font (size 1.524 1.524)))
    )
    (property "Value" "R_0R_0402" (at 89.535 145.415 0)
      (effects (font (size 1.524 1.524)) hide)
    )
    (property "Footprint" "kria-k26-devboard-footprints:R_0402_1005Metric" (at 94.615 136.525 0)
      (effects (font (size 1.27 1.27) (thickness 0.15)) (justify left bottom) hide)
    )
    (property "Datasheet" "https://industrial.panasonic.com/cdbs/www-data/pdf/RDA0000/AOA0000C301.pdf" (at 89.535 141.605 0)
      (effects (font (size 1.27 1.27) (thickness 0.15)) (justify left bottom) hide)
    )
    (property "Manufacturer" "Panasonic" (at 94.615 131.445 0)
      (effects (font (size 1.27 1.27) (thickness 0.15)) (justify left bottom) hide)
    )
    (property "MPN" "ERJ2GE0R00X" (at 94.615 133.985 0)
      (effects (font (size 1.27 1.27) (thickness 0.15)) (justify left bottom) hide)
    )
    (property "Val" "0R" (at 92.075 139.7 0)
      (effects (font (size 1.27 1.27) (thickness 0.15)))
    )
    (property "License" "Apache-2.0" (at 109.855 167.005 0)
      (effects (font (size 1.27 1.27) (thickness 0.15)) (justify left bottom) hide)
    )
    (property "Author" "Antmicro" (at 109.855 169.545 0)
      (effects (font (size 1.27 1.27) (thickness 0.15)) (justify left bottom) hide)
    )
    (property "Tolerance" "~" (at 109.855 151.765 0)
      (effects (font (size 1.27 1.27)) (justify left bottom) hide)
    )
    (property "Current" "1A" (at 109.855 172.085 0)
      (effects (font (size 1.27 1.27) (thickness 0.15)) (justify left bottom) hide)
    )
    (pin "1")
    (pin "2")
    (instances
      (project "kria-k26-devboard"
        (path ""
          (reference "R165") (unit 1)
        )
      )
    )
  )

  (symbol (lib_id "kria-k26-devboard:R_0R_22.4A_0603") (at 129.54 38.1 0) (unit 1)
    (in_bom yes) (on_board yes) (dnp no)
    (property "Reference" "R160" (at 132.08 34.29 0)
      (effects (font (size 1.524 1.524)))
    )
    (property "Value" "R_0R_22.4A_0603" (at 129.54 41.91 0)
      (effects (font (size 1.27 1.27) (thickness 0.15)) (justify left bottom) hide)
    )
    (property "Footprint" "kria-k26-devboard-footprints:R_0603_1608Metric" (at 134.62 33.02 0)
      (effects (font (size 1.27 1.27) (thickness 0.15)) (justify left bottom) hide)
    )
    (property "Datasheet" "https://fscdn.rohm.com/en/products/databook/datasheet/passive/resistor/chip_resistor/pmr-jpw-e.pdf" (at 129.54 38.1 0)
      (effects (font (size 1.27 1.27) (thickness 0.15)) (justify left bottom) hide)
    )
    (property "Manufacturer" "ROHM Semiconductor" (at 134.62 27.94 0)
      (effects (font (size 1.27 1.27) (thickness 0.15)) (justify left bottom) hide)
    )
    (property "MPN" "PMR03EZPJ000" (at 134.62 30.48 0)
      (effects (font (size 1.27 1.27) (thickness 0.15)) (justify left bottom) hide)
    )
    (property "Val" "0R" (at 132.08 36.195 0)
      (effects (font (size 1.27 1.27) (thickness 0.15)))
    )
    (property "Author" "Antmicro" (at 152.4 60.96 0)
      (effects (font (size 1.27 1.27) (thickness 0.15)) (justify left bottom) hide)
    )
    (property "License" "Apache-2.0" (at 152.4 63.5 0)
      (effects (font (size 1.27 1.27) (thickness 0.15)) (justify left bottom) hide)
    )
    (property "Max. Curr." "22.4A" (at 132.08 40.005 0)
      (effects (font (size 1.27 1.27) (thickness 0.15)))
    )
    (pin "1")
    (pin "2")
    (instances
      (project "kria-k26-devboard"
        (path ""
          (reference "R160") (unit 1)
        )
      )
    )
  )

  (symbol (lib_id "kria-k26-devboard:GND") (at 370.84 84.455 0) (unit 1)
    (in_bom yes) (on_board yes) (dnp no) (fields_autoplaced)
    (property "Reference" "#PWR0151" (at 370.84 90.805 0)
      (effects (font (size 1.27 1.27)) hide)
    )
    (property "Value" "GND" (at 370.84 89.535 0)
      (effects (font (size 1.27 1.27)))
    )
    (property "Footprint" "" (at 379.73 92.075 0)
      (effects (font (size 1.27 1.27) (thickness 0.15)) (justify left bottom) hide)
    )
    (property "Datasheet" "" (at 379.73 97.155 0)
      (effects (font (size 1.27 1.27) (thickness 0.15)) (justify left bottom) hide)
    )
    (property "Author" "Antmicro" (at 379.73 92.075 0)
      (effects (font (size 1.27 1.27) (thickness 0.15)) (justify left bottom) hide)
    )
    (property "License" "Apache-2.0" (at 379.73 94.615 0)
      (effects (font (size 1.27 1.27) (thickness 0.15)) (justify left bottom) hide)
    )
    (pin "1")
    (instances
      (project "kria-k26-devboard"
        (path ""
          (reference "#PWR0151") (unit 1)
        )
      )
    )
  )

  (symbol (lib_id "kria-k26-devboard:R_0R_22.4A_0603") (at 387.35 34.29 0) (unit 1)
    (in_bom yes) (on_board yes) (dnp no)
    (property "Reference" "R158" (at 389.89 30.48 0)
      (effects (font (size 1.524 1.524)))
    )
    (property "Value" "R_0R_22.4A_0603" (at 387.35 38.1 0)
      (effects (font (size 1.27 1.27) (thickness 0.15)) (justify left bottom) hide)
    )
    (property "Footprint" "kria-k26-devboard-footprints:R_0603_1608Metric" (at 392.43 29.21 0)
      (effects (font (size 1.27 1.27) (thickness 0.15)) (justify left bottom) hide)
    )
    (property "Datasheet" "https://fscdn.rohm.com/en/products/databook/datasheet/passive/resistor/chip_resistor/pmr-jpw-e.pdf" (at 387.35 34.29 0)
      (effects (font (size 1.27 1.27) (thickness 0.15)) (justify left bottom) hide)
    )
    (property "Manufacturer" "ROHM Semiconductor" (at 392.43 24.13 0)
      (effects (font (size 1.27 1.27) (thickness 0.15)) (justify left bottom) hide)
    )
    (property "MPN" "PMR03EZPJ000" (at 392.43 26.67 0)
      (effects (font (size 1.27 1.27) (thickness 0.15)) (justify left bottom) hide)
    )
    (property "Val" "0R" (at 389.89 32.385 0)
      (effects (font (size 1.27 1.27) (thickness 0.15)))
    )
    (property "Author" "Antmicro" (at 410.21 57.15 0)
      (effects (font (size 1.27 1.27) (thickness 0.15)) (justify left bottom) hide)
    )
    (property "License" "Apache-2.0" (at 410.21 59.69 0)
      (effects (font (size 1.27 1.27) (thickness 0.15)) (justify left bottom) hide)
    )
    (property "Max. Curr." "22.4A" (at 389.89 36.195 0)
      (effects (font (size 1.27 1.27) (thickness 0.15)))
    )
    (pin "1")
    (pin "2")
    (instances
      (project "kria-k26-devboard"
        (path ""
          (reference "R158") (unit 1)
        )
      )
    )
  )

  (symbol (lib_id "kria-k26-devboard:GND") (at 360.045 50.8 0) (unit 1)
    (in_bom yes) (on_board yes) (dnp no) (fields_autoplaced)
    (property "Reference" "#PWR0146" (at 360.045 57.15 0)
      (effects (font (size 1.27 1.27)) hide)
    )
    (property "Value" "GND" (at 360.045 55.88 0)
      (effects (font (size 1.27 1.27)))
    )
    (property "Footprint" "" (at 368.935 58.42 0)
      (effects (font (size 1.27 1.27) (thickness 0.15)) (justify left bottom) hide)
    )
    (property "Datasheet" "" (at 368.935 63.5 0)
      (effects (font (size 1.27 1.27) (thickness 0.15)) (justify left bottom) hide)
    )
    (property "Author" "Antmicro" (at 368.935 58.42 0)
      (effects (font (size 1.27 1.27) (thickness 0.15)) (justify left bottom) hide)
    )
    (property "License" "Apache-2.0" (at 368.935 60.96 0)
      (effects (font (size 1.27 1.27) (thickness 0.15)) (justify left bottom) hide)
    )
    (pin "1")
    (instances
      (project "kria-k26-devboard"
        (path ""
          (reference "#PWR0146") (unit 1)
        )
      )
    )
  )

  (symbol (lib_id "kria-k26-devboard:GND") (at 320.04 77.47 0) (unit 1)
    (in_bom yes) (on_board yes) (dnp no) (fields_autoplaced)
    (property "Reference" "#PWR0150" (at 320.04 83.82 0)
      (effects (font (size 1.27 1.27)) hide)
    )
    (property "Value" "GND" (at 320.04 82.55 0)
      (effects (font (size 1.27 1.27)))
    )
    (property "Footprint" "" (at 328.93 85.09 0)
      (effects (font (size 1.27 1.27) (thickness 0.15)) (justify left bottom) hide)
    )
    (property "Datasheet" "" (at 328.93 90.17 0)
      (effects (font (size 1.27 1.27) (thickness 0.15)) (justify left bottom) hide)
    )
    (property "Author" "Antmicro" (at 328.93 85.09 0)
      (effects (font (size 1.27 1.27) (thickness 0.15)) (justify left bottom) hide)
    )
    (property "License" "Apache-2.0" (at 328.93 87.63 0)
      (effects (font (size 1.27 1.27) (thickness 0.15)) (justify left bottom) hide)
    )
    (pin "1")
    (instances
      (project "kria-k26-devboard"
        (path ""
          (reference "#PWR0150") (unit 1)
        )
      )
    )
  )

  (symbol (lib_id "kria-k26-devboard:GND") (at 54.61 109.855 0) (unit 1)
    (in_bom yes) (on_board yes) (dnp no) (fields_autoplaced)
    (property "Reference" "#PWR0137" (at 54.61 116.205 0)
      (effects (font (size 1.27 1.27)) hide)
    )
    (property "Value" "GND" (at 54.61 114.3 0)
      (effects (font (size 1.27 1.27)))
    )
    (property "Footprint" "" (at 63.5 117.475 0)
      (effects (font (size 1.27 1.27) (thickness 0.15)) (justify left bottom) hide)
    )
    (property "Datasheet" "" (at 63.5 122.555 0)
      (effects (font (size 1.27 1.27) (thickness 0.15)) (justify left bottom) hide)
    )
    (property "Author" "Antmicro" (at 63.5 117.475 0)
      (effects (font (size 1.27 1.27) (thickness 0.15)) (justify left bottom) hide)
    )
    (property "License" "Apache-2.0" (at 63.5 120.015 0)
      (effects (font (size 1.27 1.27) (thickness 0.15)) (justify left bottom) hide)
    )
    (pin "1")
    (instances
      (project "kria-k26-devboard"
        (path ""
          (reference "#PWR0137") (unit 1)
        )
      )
    )
  )

  (symbol (lib_id "kria-k26-devboard:R_0R_22.4A_0603") (at 386.08 66.04 0) (unit 1)
    (in_bom yes) (on_board yes) (dnp no)
    (property "Reference" "R159" (at 388.62 62.23 0)
      (effects (font (size 1.524 1.524)))
    )
    (property "Value" "R_0R_22.4A_0603" (at 386.08 69.85 0)
      (effects (font (size 1.27 1.27) (thickness 0.15)) (justify left bottom) hide)
    )
    (property "Footprint" "kria-k26-devboard-footprints:R_0603_1608Metric" (at 391.16 60.96 0)
      (effects (font (size 1.27 1.27) (thickness 0.15)) (justify left bottom) hide)
    )
    (property "Datasheet" "https://fscdn.rohm.com/en/products/databook/datasheet/passive/resistor/chip_resistor/pmr-jpw-e.pdf" (at 386.08 66.04 0)
      (effects (font (size 1.27 1.27) (thickness 0.15)) (justify left bottom) hide)
    )
    (property "Manufacturer" "ROHM Semiconductor" (at 391.16 55.88 0)
      (effects (font (size 1.27 1.27) (thickness 0.15)) (justify left bottom) hide)
    )
    (property "MPN" "PMR03EZPJ000" (at 391.16 58.42 0)
      (effects (font (size 1.27 1.27) (thickness 0.15)) (justify left bottom) hide)
    )
    (property "Val" "0R" (at 388.62 64.135 0)
      (effects (font (size 1.27 1.27) (thickness 0.15)))
    )
    (property "Author" "Antmicro" (at 408.94 88.9 0)
      (effects (font (size 1.27 1.27) (thickness 0.15)) (justify left bottom) hide)
    )
    (property "License" "Apache-2.0" (at 408.94 91.44 0)
      (effects (font (size 1.27 1.27) (thickness 0.15)) (justify left bottom) hide)
    )
    (property "Max. Curr." "22.4A" (at 388.62 67.945 0)
      (effects (font (size 1.27 1.27) (thickness 0.15)))
    )
    (pin "1")
    (pin "2")
    (instances
      (project "kria-k26-devboard"
        (path ""
          (reference "R159") (unit 1)
        )
      )
    )
  )

  (symbol (lib_id "kria-k26-devboard:R_1k_0402") (at 146.05 241.935 0) (unit 1)
    (in_bom yes) (on_board yes) (dnp no)
    (property "Reference" "R129" (at 148.59 237.49 0)
      (effects (font (size 1.524 1.524)))
    )
    (property "Value" "R_1k_0402" (at 146.05 245.745 0)
      (effects (font (size 1.27 1.27) (thickness 0.15)) (justify left bottom) hide)
    )
    (property "Footprint" "kria-k26-devboard-footprints:R_0402_1005Metric" (at 151.13 236.855 0)
      (effects (font (size 1.27 1.27) (thickness 0.15)) (justify left bottom) hide)
    )
    (property "Datasheet" "https://www.bourns.com/docs/product-datasheets/cr.pdf" (at 146.05 241.935 0)
      (effects (font (size 1.27 1.27) (thickness 0.15)) (justify left bottom) hide)
    )
    (property "Manufacturer" "Bourns" (at 151.13 231.775 0)
      (effects (font (size 1.27 1.27) (thickness 0.15)) (justify left bottom) hide)
    )
    (property "MPN" "CR0402-FX-1001GLF" (at 151.13 234.315 0)
      (effects (font (size 1.27 1.27) (thickness 0.15)) (justify left bottom) hide)
    )
    (property "Val" "1k" (at 148.59 239.395 0)
      (effects (font (size 1.27 1.27) (thickness 0.15)))
    )
    (property "License" "Apache-2.0" (at 166.37 267.335 0)
      (effects (font (size 1.27 1.27) (thickness 0.15)) (justify left bottom) hide)
    )
    (property "Author" "Antmicro" (at 166.37 269.875 0)
      (effects (font (size 1.27 1.27) (thickness 0.15)) (justify left bottom) hide)
    )
    (property "Tolerance" "1%" (at 166.37 252.095 0)
      (effects (font (size 1.27 1.27)) (justify left bottom) hide)
    )
    (pin "1")
    (pin "2")
    (instances
      (project "kria-k26-devboard"
        (path ""
          (reference "R129") (unit 1)
        )
      )
    )
  )

  (symbol (lib_id "kria-k26-devboard:R_510R_0402") (at 231.14 241.935 180) (unit 1)
    (in_bom yes) (on_board yes) (dnp no)
    (property "Reference" "R141" (at 228.6 236.855 0)
      (effects (font (size 1.524 1.524)))
    )
    (property "Value" "R_510R_0402" (at 231.14 238.125 0)
      (effects (font (size 1.27 1.27) (thickness 0.15)) (justify left bottom) hide)
    )
    (property "Footprint" "kria-k26-devboard-footprints:R_0402_1005Metric" (at 226.06 247.015 0)
      (effects (font (size 1.27 1.27) (thickness 0.15)) (justify left bottom) hide)
    )
    (property "Datasheet" "https://www.bourns.com/docs/product-datasheets/cr.pdf" (at 231.14 241.935 0)
      (effects (font (size 1.27 1.27) (thickness 0.15)) (justify left bottom) hide)
    )
    (property "Manufacturer" "Bourns" (at 226.06 252.095 0)
      (effects (font (size 1.27 1.27) (thickness 0.15)) (justify left bottom) hide)
    )
    (property "MPN" "CR0402-FX-5100GLF" (at 226.06 249.555 0)
      (effects (font (size 1.27 1.27) (thickness 0.15)) (justify left bottom) hide)
    )
    (property "Val" "510R" (at 228.6 239.395 0)
      (effects (font (size 1.27 1.27) (thickness 0.15)))
    )
    (property "License" "Apache-2.0" (at 210.82 216.535 0)
      (effects (font (size 1.27 1.27) (thickness 0.15)) (justify left bottom) hide)
    )
    (property "Author" "Antmicro" (at 210.82 213.995 0)
      (effects (font (size 1.27 1.27) (thickness 0.15)) (justify left bottom) hide)
    )
    (property "Tolerance" "1%" (at 210.82 231.775 0)
      (effects (font (size 1.27 1.27)) (justify left bottom) hide)
    )
    (pin "1")
    (pin "2")
    (instances
      (project "kria-k26-devboard"
        (path ""
          (reference "R141") (unit 1)
        )
      )
    )
  )

  (symbol (lib_id "kria-k26-devboard:GND") (at 236.855 130.175 0) (unit 1)
    (in_bom yes) (on_board yes) (dnp no) (fields_autoplaced)
    (property "Reference" "#PWR0156" (at 236.855 136.525 0)
      (effects (font (size 1.27 1.27)) hide)
    )
    (property "Value" "GND" (at 236.855 135.255 0)
      (effects (font (size 1.27 1.27)))
    )
    (property "Footprint" "" (at 245.745 137.795 0)
      (effects (font (size 1.27 1.27) (thickness 0.15)) (justify left bottom) hide)
    )
    (property "Datasheet" "" (at 245.745 142.875 0)
      (effects (font (size 1.27 1.27) (thickness 0.15)) (justify left bottom) hide)
    )
    (property "Author" "Antmicro" (at 245.745 137.795 0)
      (effects (font (size 1.27 1.27) (thickness 0.15)) (justify left bottom) hide)
    )
    (property "License" "Apache-2.0" (at 245.745 140.335 0)
      (effects (font (size 1.27 1.27) (thickness 0.15)) (justify left bottom) hide)
    )
    (pin "1")
    (instances
      (project "kria-k26-devboard"
        (path ""
          (reference "#PWR0156") (unit 1)
        )
      )
    )
  )

  (symbol (lib_id "kria-k26-devboard:GND") (at 370.84 50.8 0) (unit 1)
    (in_bom yes) (on_board yes) (dnp no) (fields_autoplaced)
    (property "Reference" "#PWR0147" (at 370.84 57.15 0)
      (effects (font (size 1.27 1.27)) hide)
    )
    (property "Value" "GND" (at 370.84 55.88 0)
      (effects (font (size 1.27 1.27)))
    )
    (property "Footprint" "" (at 379.73 58.42 0)
      (effects (font (size 1.27 1.27) (thickness 0.15)) (justify left bottom) hide)
    )
    (property "Datasheet" "" (at 379.73 63.5 0)
      (effects (font (size 1.27 1.27) (thickness 0.15)) (justify left bottom) hide)
    )
    (property "Author" "Antmicro" (at 379.73 58.42 0)
      (effects (font (size 1.27 1.27) (thickness 0.15)) (justify left bottom) hide)
    )
    (property "License" "Apache-2.0" (at 379.73 60.96 0)
      (effects (font (size 1.27 1.27) (thickness 0.15)) (justify left bottom) hide)
    )
    (pin "1")
    (instances
      (project "kria-k26-devboard"
        (path ""
          (reference "#PWR0147") (unit 1)
        )
      )
    )
  )

  (symbol (lib_id "kria-k26-devboard:GND") (at 116.205 111.125 0) (unit 1)
    (in_bom yes) (on_board yes) (dnp no) (fields_autoplaced)
    (property "Reference" "#PWR0134" (at 116.205 117.475 0)
      (effects (font (size 1.27 1.27)) hide)
    )
    (property "Value" "GND" (at 116.205 115.57 0)
      (effects (font (size 1.27 1.27)))
    )
    (property "Footprint" "" (at 125.095 118.745 0)
      (effects (font (size 1.27 1.27) (thickness 0.15)) (justify left bottom) hide)
    )
    (property "Datasheet" "" (at 125.095 123.825 0)
      (effects (font (size 1.27 1.27) (thickness 0.15)) (justify left bottom) hide)
    )
    (property "Author" "Antmicro" (at 125.095 118.745 0)
      (effects (font (size 1.27 1.27) (thickness 0.15)) (justify left bottom) hide)
    )
    (property "License" "Apache-2.0" (at 125.095 121.285 0)
      (effects (font (size 1.27 1.27) (thickness 0.15)) (justify left bottom) hide)
    )
    (pin "1")
    (instances
      (project "kria-k26-devboard"
        (path ""
          (reference "#PWR0134") (unit 1)
        )
      )
    )
  )

  (symbol (lib_id "kria-k26-devboard:GND") (at 125.73 111.125 0) (unit 1)
    (in_bom yes) (on_board yes) (dnp no) (fields_autoplaced)
    (property "Reference" "#PWR0133" (at 125.73 117.475 0)
      (effects (font (size 1.27 1.27)) hide)
    )
    (property "Value" "GND" (at 125.73 115.57 0)
      (effects (font (size 1.27 1.27)))
    )
    (property "Footprint" "" (at 134.62 118.745 0)
      (effects (font (size 1.27 1.27) (thickness 0.15)) (justify left bottom) hide)
    )
    (property "Datasheet" "" (at 134.62 123.825 0)
      (effects (font (size 1.27 1.27) (thickness 0.15)) (justify left bottom) hide)
    )
    (property "Author" "Antmicro" (at 134.62 118.745 0)
      (effects (font (size 1.27 1.27) (thickness 0.15)) (justify left bottom) hide)
    )
    (property "License" "Apache-2.0" (at 134.62 121.285 0)
      (effects (font (size 1.27 1.27) (thickness 0.15)) (justify left bottom) hide)
    )
    (pin "1")
    (instances
      (project "kria-k26-devboard"
        (path ""
          (reference "#PWR0133") (unit 1)
        )
      )
    )
  )

  (symbol (lib_id "kria-k26-devboard:R_0R_22.4A_0603") (at 129.54 93.345 0) (unit 1)
    (in_bom yes) (on_board yes) (dnp no)
    (property "Reference" "R161" (at 132.08 89.535 0)
      (effects (font (size 1.524 1.524)))
    )
    (property "Value" "R_0R_22.4A_0603" (at 129.54 97.155 0)
      (effects (font (size 1.27 1.27) (thickness 0.15)) (justify left bottom) hide)
    )
    (property "Footprint" "kria-k26-devboard-footprints:R_0603_1608Metric" (at 134.62 88.265 0)
      (effects (font (size 1.27 1.27) (thickness 0.15)) (justify left bottom) hide)
    )
    (property "Datasheet" "https://fscdn.rohm.com/en/products/databook/datasheet/passive/resistor/chip_resistor/pmr-jpw-e.pdf" (at 129.54 93.345 0)
      (effects (font (size 1.27 1.27) (thickness 0.15)) (justify left bottom) hide)
    )
    (property "Manufacturer" "ROHM Semiconductor" (at 134.62 83.185 0)
      (effects (font (size 1.27 1.27) (thickness 0.15)) (justify left bottom) hide)
    )
    (property "MPN" "PMR03EZPJ000" (at 134.62 85.725 0)
      (effects (font (size 1.27 1.27) (thickness 0.15)) (justify left bottom) hide)
    )
    (property "Val" "0R" (at 132.08 91.44 0)
      (effects (font (size 1.27 1.27) (thickness 0.15)))
    )
    (property "Author" "Antmicro" (at 152.4 116.205 0)
      (effects (font (size 1.27 1.27) (thickness 0.15)) (justify left bottom) hide)
    )
    (property "License" "Apache-2.0" (at 152.4 118.745 0)
      (effects (font (size 1.27 1.27) (thickness 0.15)) (justify left bottom) hide)
    )
    (property "Max. Curr." "22.4A" (at 132.08 95.25 0)
      (effects (font (size 1.27 1.27) (thickness 0.15)))
    )
    (pin "1")
    (pin "2")
    (instances
      (project "kria-k26-devboard"
        (path ""
          (reference "R161") (unit 1)
        )
      )
    )
  )

  (symbol (lib_id "kria-k26-devboard:DTC014T_SOT-416") (at 146.685 259.715 0) (unit 1)
    (in_bom yes) (on_board yes) (dnp no) (fields_autoplaced)
    (property "Reference" "Q18" (at 157.48 258.4449 0)
      (effects (font (size 1.27 1.27)) (justify left))
    )
    (property "Value" "DTC014T_SOT-416" (at 157.48 260.9849 0)
      (effects (font (size 1.27 1.27) (thickness 0.15)) (justify left) hide)
    )
    (property "Footprint" "kria-k26-devboard-footprints:SOT-416" (at 151.765 267.335 0)
      (effects (font (size 1.27 1.27) (thickness 0.15)) (justify left bottom) hide)
    )
    (property "Datasheet" "https://www.rohm.com/datasheet?p=DTC014TEB&dist=Mouser&media=referral&source=mouser.com&campaign=Mouser" (at 146.685 259.715 0)
      (effects (font (size 1.27 1.27) (thickness 0.15)) (justify left bottom) hide)
    )
    (property "Manufacturer" "ROHM Semiconductor" (at 161.925 262.255 0)
      (effects (font (size 1.27 1.27) (thickness 0.15)) (justify left bottom) hide)
    )
    (property "MPN" "DTC014TEBTL" (at 157.48 260.9849 0)
      (effects (font (size 1.27 1.27) (thickness 0.15)) (justify left))
    )
    (property "Author" "Antmicro" (at 172.085 280.035 0)
      (effects (font (size 1.27 1.27) (thickness 0.15)) (justify left bottom) hide)
    )
    (property "License" "Apache-2.0" (at 172.085 282.575 0)
      (effects (font (size 1.27 1.27) (thickness 0.15)) (justify left bottom) hide)
    )
    (pin "1")
    (pin "2")
    (pin "3")
    (instances
      (project "kria-k26-devboard"
        (path ""
          (reference "Q18") (unit 1)
        )
      )
    )
  )

  (symbol (lib_id "kria-k26-devboard:R_147k_0402") (at 95.885 98.425 270) (unit 1)
    (in_bom yes) (on_board yes) (dnp no) (fields_autoplaced)
    (property "Reference" "R124" (at 97.663 99.695 90)
      (effects (font (size 1.524 1.524)) (justify left))
    )
    (property "Value" "R_147k_0402" (at 92.075 98.425 0)
      (effects (font (size 1.524 1.524)) hide)
    )
    (property "Footprint" "kria-k26-devboard-footprints:R_0402_1005Metric" (at 100.965 103.505 0)
      (effects (font (size 1.27 1.27) (thickness 0.15)) (justify left bottom) hide)
    )
    (property "Datasheet" "https://www.bourns.com/docs/product-datasheets/cr.pdf" (at 95.885 98.425 0)
      (effects (font (size 1.27 1.27) (thickness 0.15)) (justify left bottom) hide)
    )
    (property "Manufacturer" "Bourns" (at 106.045 103.505 0)
      (effects (font (size 1.27 1.27) (thickness 0.15)) (justify left bottom) hide)
    )
    (property "MPN" "CR0402-FX-1473GLF" (at 103.505 103.505 0)
      (effects (font (size 1.27 1.27) (thickness 0.15)) (justify left bottom) hide)
    )
    (property "Val" "147k" (at 97.663 102.8699 90)
      (effects (font (size 1.27 1.27) (thickness 0.15)) (justify left))
    )
    (property "License" "Apache-2.0" (at 70.485 118.745 0)
      (effects (font (size 1.27 1.27) (thickness 0.15)) (justify left bottom) hide)
    )
    (property "Author" "Antmicro" (at 67.945 118.745 0)
      (effects (font (size 1.27 1.27) (thickness 0.15)) (justify left bottom) hide)
    )
    (property "Tolerance" "1%" (at 85.725 118.745 0)
      (effects (font (size 1.27 1.27)) (justify left bottom) hide)
    )
    (pin "1")
    (pin "2")
    (instances
      (project "kria-k26-devboard"
        (path ""
          (reference "R124") (unit 1)
        )
      )
    )
  )

  (symbol (lib_id "kria-k26-devboard:GND") (at 196.85 204.47 0) (unit 1)
    (in_bom yes) (on_board yes) (dnp no) (fields_autoplaced)
    (property "Reference" "#PWR0160" (at 196.85 210.82 0)
      (effects (font (size 1.27 1.27)) hide)
    )
    (property "Value" "GND" (at 196.85 209.55 0)
      (effects (font (size 1.27 1.27)))
    )
    (property "Footprint" "" (at 205.74 212.09 0)
      (effects (font (size 1.27 1.27) (thickness 0.15)) (justify left bottom) hide)
    )
    (property "Datasheet" "" (at 205.74 217.17 0)
      (effects (font (size 1.27 1.27) (thickness 0.15)) (justify left bottom) hide)
    )
    (property "Author" "Antmicro" (at 205.74 212.09 0)
      (effects (font (size 1.27 1.27) (thickness 0.15)) (justify left bottom) hide)
    )
    (property "License" "Apache-2.0" (at 205.74 214.63 0)
      (effects (font (size 1.27 1.27) (thickness 0.15)) (justify left bottom) hide)
    )
    (pin "1")
    (instances
      (project "kria-k26-devboard"
        (path ""
          (reference "#PWR0160") (unit 1)
        )
      )
    )
  )

  (symbol (lib_id "kria-k26-devboard:C_22u_16V_0603") (at 127 50.8 270) (unit 1)
    (in_bom yes) (on_board yes) (dnp no)
    (property "Reference" "C199" (at 127.635 51.435 90)
      (effects (font (size 1.524 1.524)) (justify left))
    )
    (property "Value" "C_22u_16V_0603" (at 123.19 50.8 0)
      (effects (font (size 1.524 1.524)) hide)
    )
    (property "Footprint" "kria-k26-devboard-footprints:C_0603_1608Metric" (at 132.08 55.88 0)
      (effects (font (size 1.27 1.27) (thickness 0.15)) (justify left bottom) hide)
    )
    (property "Datasheet" "https://www.mouser.pl/datasheet/2/585/MLCC-1837944.pdf" (at 127 50.8 0)
      (effects (font (size 1.27 1.27) (thickness 0.15)) (justify left bottom) hide)
    )
    (property "Manufacturer" "Samsung" (at 137.16 55.88 0)
      (effects (font (size 1.27 1.27) (thickness 0.15)) (justify left bottom) hide)
    )
    (property "MPN" "CL10A226MO7JZNC" (at 134.62 55.88 0)
      (effects (font (size 1.27 1.27) (thickness 0.15)) (justify left bottom) hide)
    )
    (property "Val" "22u/16V" (at 127.635 55.245 90)
      (effects (font (size 1.27 1.27) (thickness 0.15)) (justify left))
    )
    (property "License" "Apache-2.0" (at 104.14 71.12 0)
      (effects (font (size 1.27 1.27) (thickness 0.15)) (justify left bottom) hide)
    )
    (property "Author" "Antmicro" (at 101.6 71.12 0)
      (effects (font (size 1.27 1.27) (thickness 0.15)) (justify left bottom) hide)
    )
    (property "Voltage" "" (at 99.06 71.12 0)
      (effects (font (size 1.27 1.27)) (justify left bottom) hide)
    )
    (property "Dielectric" "" (at 96.52 71.12 0)
      (effects (font (size 1.27 1.27)) (justify left bottom) hide)
    )
    (pin "1")
    (pin "2")
    (instances
      (project "kria-k26-devboard"
        (path ""
          (reference "C199") (unit 1)
        )
      )
    )
  )

  (symbol (lib_id "kria-k26-devboard:GND") (at 184.15 83.82 0) (unit 1)
    (in_bom yes) (on_board yes) (dnp no) (fields_autoplaced)
    (property "Reference" "#PWR0149" (at 184.15 90.17 0)
      (effects (font (size 1.27 1.27)) hide)
    )
    (property "Value" "GND" (at 184.15 88.9 0)
      (effects (font (size 1.27 1.27)))
    )
    (property "Footprint" "" (at 193.04 91.44 0)
      (effects (font (size 1.27 1.27) (thickness 0.15)) (justify left bottom) hide)
    )
    (property "Datasheet" "" (at 193.04 96.52 0)
      (effects (font (size 1.27 1.27) (thickness 0.15)) (justify left bottom) hide)
    )
    (property "Author" "Antmicro" (at 193.04 91.44 0)
      (effects (font (size 1.27 1.27) (thickness 0.15)) (justify left bottom) hide)
    )
    (property "License" "Apache-2.0" (at 193.04 93.98 0)
      (effects (font (size 1.27 1.27) (thickness 0.15)) (justify left bottom) hide)
    )
    (pin "1")
    (instances
      (project "kria-k26-devboard"
        (path ""
          (reference "#PWR0149") (unit 1)
        )
      )
    )
  )

  (symbol (lib_id "kria-k26-devboard:GND") (at 107.95 55.88 0) (unit 1)
    (in_bom yes) (on_board yes) (dnp no) (fields_autoplaced)
    (property "Reference" "#PWR0135" (at 107.95 62.23 0)
      (effects (font (size 1.27 1.27)) hide)
    )
    (property "Value" "GND" (at 107.95 60.325 0)
      (effects (font (size 1.27 1.27)))
    )
    (property "Footprint" "" (at 116.84 63.5 0)
      (effects (font (size 1.27 1.27) (thickness 0.15)) (justify left bottom) hide)
    )
    (property "Datasheet" "" (at 116.84 68.58 0)
      (effects (font (size 1.27 1.27) (thickness 0.15)) (justify left bottom) hide)
    )
    (property "Author" "Antmicro" (at 116.84 63.5 0)
      (effects (font (size 1.27 1.27) (thickness 0.15)) (justify left bottom) hide)
    )
    (property "License" "Apache-2.0" (at 116.84 66.04 0)
      (effects (font (size 1.27 1.27) (thickness 0.15)) (justify left bottom) hide)
    )
    (pin "1")
    (instances
      (project "kria-k26-devboard"
        (path ""
          (reference "#PWR0135") (unit 1)
        )
      )
    )
  )

  (symbol (lib_id "kria-k26-devboard:GND") (at 247.65 170.18 0) (unit 1)
    (in_bom yes) (on_board yes) (dnp no) (fields_autoplaced)
    (property "Reference" "#PWR0163" (at 247.65 176.53 0)
      (effects (font (size 1.27 1.27)) hide)
    )
    (property "Value" "GND" (at 247.65 175.26 0)
      (effects (font (size 1.27 1.27)))
    )
    (property "Footprint" "" (at 256.54 177.8 0)
      (effects (font (size 1.27 1.27) (thickness 0.15)) (justify left bottom) hide)
    )
    (property "Datasheet" "" (at 256.54 182.88 0)
      (effects (font (size 1.27 1.27) (thickness 0.15)) (justify left bottom) hide)
    )
    (property "Author" "Antmicro" (at 256.54 177.8 0)
      (effects (font (size 1.27 1.27) (thickness 0.15)) (justify left bottom) hide)
    )
    (property "License" "Apache-2.0" (at 256.54 180.34 0)
      (effects (font (size 1.27 1.27) (thickness 0.15)) (justify left bottom) hide)
    )
    (pin "1")
    (instances
      (project "kria-k26-devboard"
        (path ""
          (reference "#PWR0163") (unit 1)
        )
      )
    )
  )

  (symbol (lib_id "kria-k26-devboard:GND") (at 95.885 111.125 0) (unit 1)
    (in_bom yes) (on_board yes) (dnp no) (fields_autoplaced)
    (property "Reference" "#PWR0131" (at 95.885 117.475 0)
      (effects (font (size 1.27 1.27)) hide)
    )
    (property "Value" "GND" (at 95.885 115.57 0)
      (effects (font (size 1.27 1.27)))
    )
    (property "Footprint" "" (at 104.775 118.745 0)
      (effects (font (size 1.27 1.27) (thickness 0.15)) (justify left bottom) hide)
    )
    (property "Datasheet" "" (at 104.775 123.825 0)
      (effects (font (size 1.27 1.27) (thickness 0.15)) (justify left bottom) hide)
    )
    (property "Author" "Antmicro" (at 104.775 118.745 0)
      (effects (font (size 1.27 1.27) (thickness 0.15)) (justify left bottom) hide)
    )
    (property "License" "Apache-2.0" (at 104.775 121.285 0)
      (effects (font (size 1.27 1.27) (thickness 0.15)) (justify left bottom) hide)
    )
    (pin "1")
    (instances
      (project "kria-k26-devboard"
        (path ""
          (reference "#PWR0131") (unit 1)
        )
      )
    )
  )

  (symbol (lib_id "kria-k26-devboard:GND") (at 184.15 124.46 0) (unit 1)
    (in_bom yes) (on_board yes) (dnp no) (fields_autoplaced)
    (property "Reference" "#PWR0154" (at 184.15 130.81 0)
      (effects (font (size 1.27 1.27)) hide)
    )
    (property "Value" "GND" (at 184.15 129.54 0)
      (effects (font (size 1.27 1.27)))
    )
    (property "Footprint" "" (at 193.04 132.08 0)
      (effects (font (size 1.27 1.27) (thickness 0.15)) (justify left bottom) hide)
    )
    (property "Datasheet" "" (at 193.04 137.16 0)
      (effects (font (size 1.27 1.27) (thickness 0.15)) (justify left bottom) hide)
    )
    (property "Author" "Antmicro" (at 193.04 132.08 0)
      (effects (font (size 1.27 1.27) (thickness 0.15)) (justify left bottom) hide)
    )
    (property "License" "Apache-2.0" (at 193.04 134.62 0)
      (effects (font (size 1.27 1.27) (thickness 0.15)) (justify left bottom) hide)
    )
    (pin "1")
    (instances
      (project "kria-k26-devboard"
        (path ""
          (reference "#PWR0154") (unit 1)
        )
      )
    )
  )
)
